(kicad_sch (version 20211123) (generator eeschema)

  (paper "A3")

  (title_block
    (title "SA800U (Snapdragon 845) Baseboard")
    (date "2023-10-19")
    (rev "1.0.3")
    (company "Antmicro Ltd.")
    (comment 1 "www.antmicro.com")
  )

  (junction (at 108.585 177.165) (diameter 0) (color 0 0 0 0)
  )
  (junction (at 156.845 88.9) (diameter 0) (color 0 0 0 0)
  )
  (junction (at 123.19 147.828) (diameter 0) (color 0 0 0 0)
  )
  (junction (at 114.3 88.9) (diameter 0) (color 0 0 0 0)
  )
  (junction (at 154.94 125.095) (diameter 0) (color 0 0 0 0)
  )
  (junction (at 171.704 170.815) (diameter 0) (color 0 0 0 0)
  )
  (junction (at 215.9 88.265) (diameter 0) (color 0 0 0 0)
  )
  (junction (at 123.19 155.702) (diameter 0) (color 0 0 0 0)
  )
  (junction (at 226.695 78.105) (diameter 0) (color 0 0 0 0)
  )
  (junction (at 241.808 159.385) (diameter 0) (color 0 0 0 0)
  )
  (junction (at 146.685 78.74) (diameter 0) (color 0 0 0 0)
  )
  (junction (at 175.26 114.935) (diameter 0) (color 0 0 0 0)
  )
  (junction (at 134.62 127.635) (diameter 0) (color 0 0 0 0)
  )
  (junction (at 205.74 125.095) (diameter 0) (color 0 0 0 0)
  )
  (junction (at 114.3 78.74) (diameter 0) (color 0 0 0 0)
  )
  (junction (at 175.26 117.475) (diameter 0) (color 0 0 0 0)
  )
  (junction (at 161.925 127.635) (diameter 0) (color 0 0 0 0)
  )
  (junction (at 199.39 88.265) (diameter 0) (color 0 0 0 0)
  )
  (junction (at 258.445 78.105) (diameter 0) (color 0 0 0 0)
  )
  (junction (at 135.89 88.9) (diameter 0) (color 0 0 0 0)
  )
  (junction (at 113.665 169.545) (diameter 0) (color 0 0 0 0)
  )
  (junction (at 142.875 130.175) (diameter 0) (color 0 0 0 0)
  )
  (junction (at 248.285 78.105) (diameter 0) (color 0 0 0 0)
  )
  (junction (at 126.365 125.095) (diameter 0) (color 0 0 0 0)
  )
  (junction (at 205.74 120.015) (diameter 0) (color 0 0 0 0)
  )
  (junction (at 213.106 78.105) (diameter 0) (color 0 0 0 0)
  )
  (junction (at 134.62 114.935) (diameter 0) (color 0 0 0 0)
  )
  (junction (at 237.49 78.105) (diameter 0) (color 0 0 0 0)
  )
  (junction (at 125.095 78.74) (diameter 0) (color 0 0 0 0)
  )
  (junction (at 168.275 130.175) (diameter 0) (color 0 0 0 0)
  )
  (junction (at 199.39 78.105) (diameter 0) (color 0 0 0 0)
  )
  (junction (at 116.332 78.74) (diameter 0) (color 0 0 0 0)
  )
  (junction (at 226.695 88.265) (diameter 0) (color 0 0 0 0)
  )
  (junction (at 167.005 78.74) (diameter 0) (color 0 0 0 0)
  )
  (junction (at 205.74 122.555) (diameter 0) (color 0 0 0 0)
  )
  (junction (at 135.89 78.74) (diameter 0) (color 0 0 0 0)
  )
  (junction (at 156.845 78.74) (diameter 0) (color 0 0 0 0)
  )
  (junction (at 248.285 88.265) (diameter 0) (color 0 0 0 0)
  )
  (junction (at 160.655 158.115) (diameter 0) (color 0 0 0 0)
  )
  (junction (at 237.49 88.265) (diameter 0) (color 0 0 0 0)
  )
  (junction (at 103.505 169.545) (diameter 0) (color 0 0 0 0)
  )
  (junction (at 146.685 88.9) (diameter 0) (color 0 0 0 0)
  )
  (junction (at 203.454 78.105) (diameter 0) (color 0 0 0 0)
  )
  (junction (at 171.704 163.195) (diameter 0) (color 0 0 0 0)
  )
  (junction (at 207.645 114.935) (diameter 0) (color 0 0 0 0)
  )
  (junction (at 292.1 169.545) (diameter 0) (color 0 0 0 0)
  )
  (junction (at 215.9 78.105) (diameter 0) (color 0 0 0 0)
  )
  (junction (at 126.365 114.935) (diameter 0) (color 0 0 0 0)
  )
  (junction (at 125.095 88.9) (diameter 0) (color 0 0 0 0)
  )

  (no_connect (at 204.47 160.655))

  (wire (pts (xy 115.57 137.795) (xy 176.53 137.795))
    (stroke (width 0) (type default) (color 0 0 0 0))
  )
  (wire (pts (xy 226.695 85.725) (xy 226.695 88.265))
    (stroke (width 0) (type default) (color 0 0 0 0))
  )
  (wire (pts (xy 146.685 78.74) (xy 146.685 81.28))
    (stroke (width 0) (type default) (color 0 0 0 0))
  )
  (wire (pts (xy 114.3 78.74) (xy 116.332 78.74))
    (stroke (width 0) (type default) (color 0 0 0 0))
  )
  (wire (pts (xy 145.669 142.875) (xy 176.53 142.875))
    (stroke (width 0) (type default) (color 0 0 0 0))
  )
  (wire (pts (xy 161.925 123.825) (xy 161.925 127.635))
    (stroke (width 0) (type default) (color 0 0 0 0))
  )
  (wire (pts (xy 114.3 88.9) (xy 114.3 91.44))
    (stroke (width 0) (type default) (color 0 0 0 0))
  )
  (wire (pts (xy 142.875 121.158) (xy 142.875 130.175))
    (stroke (width 0) (type default) (color 0 0 0 0))
  )
  (wire (pts (xy 171.704 169.672) (xy 171.704 170.815))
    (stroke (width 0) (type default) (color 0 0 0 0))
  )
  (wire (pts (xy 203.454 76.2) (xy 203.454 78.105))
    (stroke (width 0) (type default) (color 0 0 0 0))
  )
  (wire (pts (xy 123.19 114.935) (xy 126.365 114.935))
    (stroke (width 0) (type default) (color 0 0 0 0))
  )
  (wire (pts (xy 115.57 132.715) (xy 176.53 132.715))
    (stroke (width 0) (type default) (color 0 0 0 0))
  )
  (wire (pts (xy 211.455 78.105) (xy 213.106 78.105))
    (stroke (width 0) (type default) (color 0 0 0 0))
  )
  (wire (pts (xy 104.775 169.545) (xy 103.505 169.545))
    (stroke (width 0) (type default) (color 0 0 0 0))
  )
  (wire (pts (xy 146.685 88.9) (xy 156.845 88.9))
    (stroke (width 0) (type default) (color 0 0 0 0))
  )
  (wire (pts (xy 140.589 142.875) (xy 115.57 142.875))
    (stroke (width 0) (type default) (color 0 0 0 0))
  )
  (wire (pts (xy 241.808 156.845) (xy 241.808 159.385))
    (stroke (width 0) (type default) (color 0 0 0 0))
  )
  (wire (pts (xy 258.445 80.645) (xy 258.445 78.105))
    (stroke (width 0) (type default) (color 0 0 0 0))
  )
  (wire (pts (xy 258.445 78.105) (xy 278.13 78.105))
    (stroke (width 0) (type default) (color 0 0 0 0))
  )
  (wire (pts (xy 113.665 169.545) (xy 123.825 169.545))
    (stroke (width 0) (type default) (color 0 0 0 0))
  )
  (wire (pts (xy 204.47 139.065) (xy 266.7 139.065))
    (stroke (width 0) (type default) (color 0 0 0 0))
  )
  (wire (pts (xy 204.47 151.765) (xy 266.7 151.765))
    (stroke (width 0) (type default) (color 0 0 0 0))
  )
  (wire (pts (xy 112.395 150.495) (xy 120.65 150.495))
    (stroke (width 0) (type default) (color 0 0 0 0))
  )
  (wire (pts (xy 204.47 141.605) (xy 266.7 141.605))
    (stroke (width 0) (type default) (color 0 0 0 0))
  )
  (wire (pts (xy 199.39 78.105) (xy 199.39 80.645))
    (stroke (width 0) (type default) (color 0 0 0 0))
  )
  (wire (pts (xy 237.49 85.725) (xy 237.49 88.265))
    (stroke (width 0) (type default) (color 0 0 0 0))
  )
  (wire (pts (xy 103.505 175.895) (xy 103.505 177.165))
    (stroke (width 0) (type default) (color 0 0 0 0))
  )
  (wire (pts (xy 134.62 116.078) (xy 134.62 114.935))
    (stroke (width 0) (type default) (color 0 0 0 0))
  )
  (wire (pts (xy 123.19 155.702) (xy 130.175 155.702))
    (stroke (width 0) (type default) (color 0 0 0 0))
  )
  (wire (pts (xy 204.47 158.115) (xy 221.615 158.115))
    (stroke (width 0) (type default) (color 0 0 0 0))
  )
  (wire (pts (xy 215.9 78.105) (xy 215.9 80.645))
    (stroke (width 0) (type default) (color 0 0 0 0))
  )
  (wire (pts (xy 115.57 135.255) (xy 176.53 135.255))
    (stroke (width 0) (type default) (color 0 0 0 0))
  )
  (wire (pts (xy 204.47 163.195) (xy 221.615 163.195))
    (stroke (width 0) (type default) (color 0 0 0 0))
  )
  (wire (pts (xy 215.9 88.265) (xy 226.695 88.265))
    (stroke (width 0) (type default) (color 0 0 0 0))
  )
  (wire (pts (xy 125.095 88.9) (xy 135.89 88.9))
    (stroke (width 0) (type default) (color 0 0 0 0))
  )
  (wire (pts (xy 167.005 86.36) (xy 167.005 88.9))
    (stroke (width 0) (type default) (color 0 0 0 0))
  )
  (wire (pts (xy 248.285 78.105) (xy 258.445 78.105))
    (stroke (width 0) (type default) (color 0 0 0 0))
  )
  (wire (pts (xy 103.505 170.815) (xy 103.505 169.545))
    (stroke (width 0) (type default) (color 0 0 0 0))
  )
  (wire (pts (xy 175.26 120.015) (xy 175.26 117.475))
    (stroke (width 0) (type default) (color 0 0 0 0))
  )
  (wire (pts (xy 123.19 147.828) (xy 130.175 147.828))
    (stroke (width 0) (type default) (color 0 0 0 0))
  )
  (wire (pts (xy 125.095 86.36) (xy 125.095 88.9))
    (stroke (width 0) (type default) (color 0 0 0 0))
  )
  (wire (pts (xy 204.47 149.225) (xy 266.7 149.225))
    (stroke (width 0) (type default) (color 0 0 0 0))
  )
  (wire (pts (xy 204.47 120.015) (xy 205.74 120.015))
    (stroke (width 0) (type default) (color 0 0 0 0))
  )
  (wire (pts (xy 135.89 88.9) (xy 146.685 88.9))
    (stroke (width 0) (type default) (color 0 0 0 0))
  )
  (wire (pts (xy 134.62 121.158) (xy 134.62 127.635))
    (stroke (width 0) (type default) (color 0 0 0 0))
  )
  (wire (pts (xy 176.53 160.655) (xy 171.704 160.655))
    (stroke (width 0) (type default) (color 0 0 0 0))
  )
  (wire (pts (xy 114.3 86.36) (xy 114.3 88.9))
    (stroke (width 0) (type default) (color 0 0 0 0))
  )
  (wire (pts (xy 241.808 159.385) (xy 241.808 173.355))
    (stroke (width 0) (type default) (color 0 0 0 0))
  )
  (wire (pts (xy 175.26 117.475) (xy 175.26 114.935))
    (stroke (width 0) (type default) (color 0 0 0 0))
  )
  (wire (pts (xy 226.695 78.105) (xy 226.695 80.645))
    (stroke (width 0) (type default) (color 0 0 0 0))
  )
  (wire (pts (xy 130.175 153.035) (xy 130.175 155.702))
    (stroke (width 0) (type default) (color 0 0 0 0))
  )
  (wire (pts (xy 171.704 170.815) (xy 171.704 172.085))
    (stroke (width 0) (type default) (color 0 0 0 0))
  )
  (wire (pts (xy 120.65 150.495) (xy 120.65 147.828))
    (stroke (width 0) (type default) (color 0 0 0 0))
  )
  (wire (pts (xy 255.27 169.545) (xy 266.7 169.545))
    (stroke (width 0) (type default) (color 0 0 0 0))
  )
  (wire (pts (xy 258.445 88.265) (xy 258.445 85.725))
    (stroke (width 0) (type default) (color 0 0 0 0))
  )
  (wire (pts (xy 114.3 88.9) (xy 125.095 88.9))
    (stroke (width 0) (type default) (color 0 0 0 0))
  )
  (wire (pts (xy 156.845 88.9) (xy 167.005 88.9))
    (stroke (width 0) (type default) (color 0 0 0 0))
  )
  (wire (pts (xy 113.665 177.165) (xy 108.585 177.165))
    (stroke (width 0) (type default) (color 0 0 0 0))
  )
  (wire (pts (xy 241.808 156.845) (xy 266.7 156.845))
    (stroke (width 0) (type default) (color 0 0 0 0))
  )
  (wire (pts (xy 115.57 125.095) (xy 126.365 125.095))
    (stroke (width 0) (type default) (color 0 0 0 0))
  )
  (wire (pts (xy 142.875 130.175) (xy 168.275 130.175))
    (stroke (width 0) (type default) (color 0 0 0 0))
  )
  (wire (pts (xy 288.29 169.545) (xy 292.1 169.545))
    (stroke (width 0) (type default) (color 0 0 0 0))
  )
  (wire (pts (xy 173.736 170.815) (xy 171.704 170.815))
    (stroke (width 0) (type default) (color 0 0 0 0))
  )
  (wire (pts (xy 311.785 156.845) (xy 298.196 156.845))
    (stroke (width 0) (type default) (color 0 0 0 0))
  )
  (wire (pts (xy 176.53 117.475) (xy 175.26 117.475))
    (stroke (width 0) (type default) (color 0 0 0 0))
  )
  (wire (pts (xy 255.27 167.005) (xy 266.7 167.005))
    (stroke (width 0) (type default) (color 0 0 0 0))
  )
  (wire (pts (xy 115.57 140.335) (xy 176.53 140.335))
    (stroke (width 0) (type default) (color 0 0 0 0))
  )
  (wire (pts (xy 170.434 163.195) (xy 171.704 163.195))
    (stroke (width 0) (type default) (color 0 0 0 0))
  )
  (wire (pts (xy 112.395 153.035) (xy 120.65 153.035))
    (stroke (width 0) (type default) (color 0 0 0 0))
  )
  (wire (pts (xy 160.655 158.115) (xy 160.655 167.005))
    (stroke (width 0) (type default) (color 0 0 0 0))
  )
  (wire (pts (xy 171.704 160.655) (xy 171.704 163.195))
    (stroke (width 0) (type default) (color 0 0 0 0))
  )
  (wire (pts (xy 115.57 127.635) (xy 134.62 127.635))
    (stroke (width 0) (type default) (color 0 0 0 0))
  )
  (wire (pts (xy 292.1 169.291) (xy 292.1 169.545))
    (stroke (width 0) (type default) (color 0 0 0 0))
  )
  (wire (pts (xy 134.62 127.635) (xy 161.925 127.635))
    (stroke (width 0) (type default) (color 0 0 0 0))
  )
  (wire (pts (xy 126.365 114.935) (xy 134.62 114.935))
    (stroke (width 0) (type default) (color 0 0 0 0))
  )
  (wire (pts (xy 248.285 80.645) (xy 248.285 78.105))
    (stroke (width 0) (type default) (color 0 0 0 0))
  )
  (wire (pts (xy 148.209 145.415) (xy 176.53 145.415))
    (stroke (width 0) (type default) (color 0 0 0 0))
  )
  (wire (pts (xy 205.74 122.555) (xy 205.74 125.095))
    (stroke (width 0) (type default) (color 0 0 0 0))
  )
  (wire (pts (xy 157.353 158.115) (xy 160.655 158.115))
    (stroke (width 0) (type default) (color 0 0 0 0))
  )
  (wire (pts (xy 213.106 78.105) (xy 215.9 78.105))
    (stroke (width 0) (type default) (color 0 0 0 0))
  )
  (wire (pts (xy 237.49 88.265) (xy 248.285 88.265))
    (stroke (width 0) (type default) (color 0 0 0 0))
  )
  (wire (pts (xy 116.332 78.74) (xy 125.095 78.74))
    (stroke (width 0) (type default) (color 0 0 0 0))
  )
  (wire (pts (xy 154.94 123.825) (xy 154.94 125.095))
    (stroke (width 0) (type default) (color 0 0 0 0))
  )
  (wire (pts (xy 135.89 78.74) (xy 135.89 81.28))
    (stroke (width 0) (type default) (color 0 0 0 0))
  )
  (wire (pts (xy 199.39 78.105) (xy 203.454 78.105))
    (stroke (width 0) (type default) (color 0 0 0 0))
  )
  (wire (pts (xy 126.365 125.095) (xy 154.94 125.095))
    (stroke (width 0) (type default) (color 0 0 0 0))
  )
  (wire (pts (xy 160.655 157.48) (xy 160.655 158.115))
    (stroke (width 0) (type default) (color 0 0 0 0))
  )
  (wire (pts (xy 292.1 169.545) (xy 292.1 172.085))
    (stroke (width 0) (type default) (color 0 0 0 0))
  )
  (wire (pts (xy 160.655 158.115) (xy 176.53 158.115))
    (stroke (width 0) (type default) (color 0 0 0 0))
  )
  (wire (pts (xy 116.332 77.597) (xy 116.332 78.74))
    (stroke (width 0) (type default) (color 0 0 0 0))
  )
  (wire (pts (xy 175.26 114.935) (xy 176.53 114.935))
    (stroke (width 0) (type default) (color 0 0 0 0))
  )
  (wire (pts (xy 103.505 169.545) (xy 94.615 169.545))
    (stroke (width 0) (type default) (color 0 0 0 0))
  )
  (wire (pts (xy 248.285 88.265) (xy 248.285 85.725))
    (stroke (width 0) (type default) (color 0 0 0 0))
  )
  (wire (pts (xy 204.47 133.985) (xy 266.7 133.985))
    (stroke (width 0) (type default) (color 0 0 0 0))
  )
  (wire (pts (xy 237.49 78.105) (xy 237.49 80.645))
    (stroke (width 0) (type default) (color 0 0 0 0))
  )
  (wire (pts (xy 125.095 78.74) (xy 135.89 78.74))
    (stroke (width 0) (type default) (color 0 0 0 0))
  )
  (wire (pts (xy 288.29 159.385) (xy 311.785 159.385))
    (stroke (width 0) (type default) (color 0 0 0 0))
  )
  (wire (pts (xy 167.005 78.74) (xy 176.53 78.74))
    (stroke (width 0) (type default) (color 0 0 0 0))
  )
  (wire (pts (xy 187.325 78.105) (xy 199.39 78.105))
    (stroke (width 0) (type default) (color 0 0 0 0))
  )
  (wire (pts (xy 171.704 163.195) (xy 171.704 164.592))
    (stroke (width 0) (type default) (color 0 0 0 0))
  )
  (wire (pts (xy 205.74 120.015) (xy 205.74 122.555))
    (stroke (width 0) (type default) (color 0 0 0 0))
  )
  (wire (pts (xy 135.89 78.74) (xy 146.685 78.74))
    (stroke (width 0) (type default) (color 0 0 0 0))
  )
  (wire (pts (xy 176.53 120.015) (xy 175.26 120.015))
    (stroke (width 0) (type default) (color 0 0 0 0))
  )
  (wire (pts (xy 248.285 88.265) (xy 258.445 88.265))
    (stroke (width 0) (type default) (color 0 0 0 0))
  )
  (wire (pts (xy 205.74 127.635) (xy 204.47 127.635))
    (stroke (width 0) (type default) (color 0 0 0 0))
  )
  (wire (pts (xy 156.845 86.36) (xy 156.845 88.9))
    (stroke (width 0) (type default) (color 0 0 0 0))
  )
  (wire (pts (xy 154.94 125.095) (xy 176.53 125.095))
    (stroke (width 0) (type default) (color 0 0 0 0))
  )
  (wire (pts (xy 237.49 78.105) (xy 248.285 78.105))
    (stroke (width 0) (type default) (color 0 0 0 0))
  )
  (wire (pts (xy 115.57 130.175) (xy 142.875 130.175))
    (stroke (width 0) (type default) (color 0 0 0 0))
  )
  (wire (pts (xy 226.695 88.265) (xy 237.49 88.265))
    (stroke (width 0) (type default) (color 0 0 0 0))
  )
  (wire (pts (xy 176.53 163.195) (xy 173.736 163.195))
    (stroke (width 0) (type default) (color 0 0 0 0))
  )
  (wire (pts (xy 123.19 154.178) (xy 123.19 155.702))
    (stroke (width 0) (type default) (color 0 0 0 0))
  )
  (wire (pts (xy 112.395 169.545) (xy 113.665 169.545))
    (stroke (width 0) (type default) (color 0 0 0 0))
  )
  (wire (pts (xy 120.65 155.702) (xy 123.19 155.702))
    (stroke (width 0) (type default) (color 0 0 0 0))
  )
  (wire (pts (xy 130.175 147.828) (xy 130.175 150.495))
    (stroke (width 0) (type default) (color 0 0 0 0))
  )
  (wire (pts (xy 123.19 147.828) (xy 123.19 149.098))
    (stroke (width 0) (type default) (color 0 0 0 0))
  )
  (wire (pts (xy 126.365 121.158) (xy 126.365 125.095))
    (stroke (width 0) (type default) (color 0 0 0 0))
  )
  (wire (pts (xy 255.27 164.465) (xy 266.7 164.465))
    (stroke (width 0) (type default) (color 0 0 0 0))
  )
  (wire (pts (xy 205.74 125.095) (xy 205.74 127.635))
    (stroke (width 0) (type default) (color 0 0 0 0))
  )
  (wire (pts (xy 113.665 175.895) (xy 113.665 177.165))
    (stroke (width 0) (type default) (color 0 0 0 0))
  )
  (wire (pts (xy 103.505 177.165) (xy 108.585 177.165))
    (stroke (width 0) (type default) (color 0 0 0 0))
  )
  (wire (pts (xy 115.57 145.415) (xy 143.129 145.415))
    (stroke (width 0) (type default) (color 0 0 0 0))
  )
  (wire (pts (xy 288.29 161.925) (xy 293.116 161.925))
    (stroke (width 0) (type default) (color 0 0 0 0))
  )
  (wire (pts (xy 108.585 177.165) (xy 108.585 180.975))
    (stroke (width 0) (type default) (color 0 0 0 0))
  )
  (wire (pts (xy 215.9 88.265) (xy 215.9 85.725))
    (stroke (width 0) (type default) (color 0 0 0 0))
  )
  (wire (pts (xy 311.785 161.925) (xy 298.196 161.925))
    (stroke (width 0) (type default) (color 0 0 0 0))
  )
  (wire (pts (xy 130.175 150.495) (xy 176.53 150.495))
    (stroke (width 0) (type default) (color 0 0 0 0))
  )
  (wire (pts (xy 173.736 163.195) (xy 173.736 170.815))
    (stroke (width 0) (type default) (color 0 0 0 0))
  )
  (wire (pts (xy 113.665 170.815) (xy 113.665 169.545))
    (stroke (width 0) (type default) (color 0 0 0 0))
  )
  (wire (pts (xy 204.47 136.525) (xy 266.7 136.525))
    (stroke (width 0) (type default) (color 0 0 0 0))
  )
  (wire (pts (xy 126.365 116.078) (xy 126.365 114.935))
    (stroke (width 0) (type default) (color 0 0 0 0))
  )
  (wire (pts (xy 199.39 88.265) (xy 215.9 88.265))
    (stroke (width 0) (type default) (color 0 0 0 0))
  )
  (wire (pts (xy 207.645 114.935) (xy 204.47 114.935))
    (stroke (width 0) (type default) (color 0 0 0 0))
  )
  (wire (pts (xy 203.454 78.105) (xy 206.375 78.105))
    (stroke (width 0) (type default) (color 0 0 0 0))
  )
  (wire (pts (xy 156.845 78.74) (xy 156.845 81.28))
    (stroke (width 0) (type default) (color 0 0 0 0))
  )
  (wire (pts (xy 241.808 159.385) (xy 266.7 159.385))
    (stroke (width 0) (type default) (color 0 0 0 0))
  )
  (wire (pts (xy 215.9 78.105) (xy 226.695 78.105))
    (stroke (width 0) (type default) (color 0 0 0 0))
  )
  (wire (pts (xy 146.685 86.36) (xy 146.685 88.9))
    (stroke (width 0) (type default) (color 0 0 0 0))
  )
  (wire (pts (xy 156.845 78.74) (xy 167.005 78.74))
    (stroke (width 0) (type default) (color 0 0 0 0))
  )
  (wire (pts (xy 168.275 130.175) (xy 176.53 130.175))
    (stroke (width 0) (type default) (color 0 0 0 0))
  )
  (wire (pts (xy 205.74 122.555) (xy 204.47 122.555))
    (stroke (width 0) (type default) (color 0 0 0 0))
  )
  (wire (pts (xy 167.005 78.74) (xy 167.005 81.28))
    (stroke (width 0) (type default) (color 0 0 0 0))
  )
  (wire (pts (xy 120.65 147.828) (xy 123.19 147.828))
    (stroke (width 0) (type default) (color 0 0 0 0))
  )
  (wire (pts (xy 161.925 127.635) (xy 176.53 127.635))
    (stroke (width 0) (type default) (color 0 0 0 0))
  )
  (wire (pts (xy 114.3 78.74) (xy 114.3 81.28))
    (stroke (width 0) (type default) (color 0 0 0 0))
  )
  (wire (pts (xy 204.47 144.145) (xy 266.7 144.145))
    (stroke (width 0) (type default) (color 0 0 0 0))
  )
  (wire (pts (xy 199.39 85.725) (xy 199.39 88.265))
    (stroke (width 0) (type default) (color 0 0 0 0))
  )
  (wire (pts (xy 108.585 174.625) (xy 108.585 177.165))
    (stroke (width 0) (type default) (color 0 0 0 0))
  )
  (wire (pts (xy 135.89 88.9) (xy 135.89 86.36))
    (stroke (width 0) (type default) (color 0 0 0 0))
  )
  (wire (pts (xy 142.875 116.078) (xy 142.875 114.935))
    (stroke (width 0) (type default) (color 0 0 0 0))
  )
  (wire (pts (xy 226.695 78.105) (xy 237.49 78.105))
    (stroke (width 0) (type default) (color 0 0 0 0))
  )
  (wire (pts (xy 150.495 158.115) (xy 152.273 158.115))
    (stroke (width 0) (type default) (color 0 0 0 0))
  )
  (wire (pts (xy 288.29 156.845) (xy 293.116 156.845))
    (stroke (width 0) (type default) (color 0 0 0 0))
  )
  (wire (pts (xy 205.74 120.015) (xy 221.615 120.015))
    (stroke (width 0) (type default) (color 0 0 0 0))
  )
  (wire (pts (xy 288.29 164.465) (xy 311.785 164.465))
    (stroke (width 0) (type default) (color 0 0 0 0))
  )
  (wire (pts (xy 95.377 78.74) (xy 92.075 78.74))
    (stroke (width 0) (type default) (color 0 0 0 0))
  )
  (wire (pts (xy 199.39 88.265) (xy 199.39 90.805))
    (stroke (width 0) (type default) (color 0 0 0 0))
  )
  (wire (pts (xy 168.275 123.825) (xy 168.275 130.175))
    (stroke (width 0) (type default) (color 0 0 0 0))
  )
  (wire (pts (xy 125.095 78.74) (xy 125.095 81.28))
    (stroke (width 0) (type default) (color 0 0 0 0))
  )
  (wire (pts (xy 205.74 125.095) (xy 204.47 125.095))
    (stroke (width 0) (type default) (color 0 0 0 0))
  )
  (wire (pts (xy 255.27 161.925) (xy 266.7 161.925))
    (stroke (width 0) (type default) (color 0 0 0 0))
  )
  (wire (pts (xy 221.615 114.935) (xy 207.645 114.935))
    (stroke (width 0) (type default) (color 0 0 0 0))
  )
  (wire (pts (xy 146.685 78.74) (xy 156.845 78.74))
    (stroke (width 0) (type default) (color 0 0 0 0))
  )
  (wire (pts (xy 120.65 153.035) (xy 120.65 155.702))
    (stroke (width 0) (type default) (color 0 0 0 0))
  )
  (wire (pts (xy 159.385 114.935) (xy 175.26 114.935))
    (stroke (width 0) (type default) (color 0 0 0 0))
  )
  (wire (pts (xy 130.175 153.035) (xy 176.53 153.035))
    (stroke (width 0) (type default) (color 0 0 0 0))
  )
  (wire (pts (xy 213.106 76.454) (xy 213.106 78.105))
    (stroke (width 0) (type default) (color 0 0 0 0))
  )
  (wire (pts (xy 204.47 146.685) (xy 266.7 146.685))
    (stroke (width 0) (type default) (color 0 0 0 0))
  )
  (wire (pts (xy 142.875 114.935) (xy 134.62 114.935))
    (stroke (width 0) (type default) (color 0 0 0 0))
  )
  (wire (pts (xy 100.457 78.74) (xy 114.3 78.74))
    (stroke (width 0) (type default) (color 0 0 0 0))
  )

  (text "Ethernet controller" (at 13.335 18.415 0)
    (effects (font (size 2.9972 2.9972) (thickness 0.5994) bold) (justify left bottom))
  )

  (label "LAN0_MDI3_N" (at 231.775 149.225 0)
    (effects (font (size 1.27 1.27)) (justify left bottom))
  )
  (label "LAN0_MDI1_P" (at 231.775 141.605 0)
    (effects (font (size 1.27 1.27)) (justify left bottom))
  )
  (label "LAN0_MDI2_P" (at 231.775 146.685 0)
    (effects (font (size 1.27 1.27)) (justify left bottom))
  )
  (label "PCIE1_RX_C_P" (at 163.195 145.415 0)
    (effects (font (size 1.27 1.27)) (justify left bottom))
  )
  (label "LAN0_MDI1_N" (at 231.775 139.065 0)
    (effects (font (size 1.27 1.27)) (justify left bottom))
  )
  (label "XTAL1" (at 112.395 150.495 0)
    (effects (font (size 1.27 1.27)) (justify left bottom))
  )
  (label "ETH_1V0" (at 221.615 120.015 180)
    (effects (font (size 1.27 1.27)) (justify right bottom))
  )
  (label "LAN0_MDI3_P" (at 231.775 151.765 0)
    (effects (font (size 1.27 1.27)) (justify left bottom))
  )
  (label "XTAL1" (at 94.615 169.545 0)
    (effects (font (size 1.27 1.27)) (justify left bottom))
  )
  (label "ETH_3V3" (at 159.385 114.935 0)
    (effects (font (size 1.27 1.27)) (justify left bottom))
  )
  (label "ETH_LED0" (at 311.785 159.385 180)
    (effects (font (size 1.27 1.27)) (justify right bottom))
  )
  (label "ETH_1V0" (at 278.13 78.105 180)
    (effects (font (size 1.27 1.27)) (justify right bottom))
  )
  (label "LAN0_MDI2_N" (at 231.775 144.145 0)
    (effects (font (size 1.27 1.27)) (justify left bottom))
  )
  (label "ETH_3V3" (at 311.785 161.925 180)
    (effects (font (size 1.27 1.27)) (justify right bottom))
  )
  (label "ETH_LED2" (at 311.785 164.465 180)
    (effects (font (size 1.27 1.27)) (justify right bottom))
  )
  (label "REG_1V0" (at 187.325 78.105 0)
    (effects (font (size 1.27 1.27)) (justify left bottom))
  )
  (label "ETH_LED0" (at 221.615 158.115 180)
    (effects (font (size 1.27 1.27)) (justify right bottom))
  )
  (label "ETH_LED2" (at 221.615 163.195 180)
    (effects (font (size 1.27 1.27)) (justify right bottom))
  )
  (label "LAN0_MDI0_P" (at 231.775 136.525 0)
    (effects (font (size 1.27 1.27)) (justify left bottom))
  )
  (label "LAN0_MDI0_N" (at 231.775 133.985 0)
    (effects (font (size 1.27 1.27)) (justify left bottom))
  )
  (label "ETH_3V3" (at 176.53 78.74 180)
    (effects (font (size 1.27 1.27)) (justify right bottom))
  )
  (label "ETH_3V3" (at 311.785 156.845 180)
    (effects (font (size 1.27 1.27)) (justify right bottom))
  )
  (label "ETH_ISOLATEB" (at 161.925 158.115 0)
    (effects (font (size 1.27 1.27)) (justify left bottom))
  )
  (label "XTAL2" (at 112.395 153.035 0)
    (effects (font (size 1.27 1.27)) (justify left bottom))
  )
  (label "REG_1V0" (at 221.615 114.935 180)
    (effects (font (size 1.27 1.27)) (justify right bottom))
  )
  (label "PCIE1_RX_C_N" (at 163.195 142.875 0)
    (effects (font (size 1.27 1.27)) (justify left bottom))
  )
  (label "XTAL2" (at 123.825 169.545 180)
    (effects (font (size 1.27 1.27)) (justify right bottom))
  )

  (global_label "PCIE1_RX_N" (shape output) (at 115.57 142.875 180) (fields_autoplaced)
    (effects (font (size 1.27 1.27)) (justify right))
    (property "Intersheet References" "${INTERSHEET_REFS}" (id 0) (at 101.9972 142.7956 0)
      (effects (font (size 1.27 1.27)) (justify right) hide)
    )
  )
  (global_label "3V3_SYS" (shape input) (at 150.495 158.115 180) (fields_autoplaced)
    (effects (font (size 1.27 1.27)) (justify right))
    (property "Intersheet References" "${INTERSHEET_REFS}" (id 0) (at 140.1879 158.0356 0)
      (effects (font (size 1.27 1.27)) (justify right) hide)
    )
  )
  (global_label "PAIR45" (shape output) (at 255.27 167.005 180) (fields_autoplaced)
    (effects (font (size 1.27 1.27)) (justify right))
    (property "Intersheet References" "${INTERSHEET_REFS}" (id 0) (at 246.2934 166.9256 0)
      (effects (font (size 1.27 1.27)) (justify right) hide)
    )
  )
  (global_label "PCIE1_WAKE_N" (shape output) (at 115.57 127.635 180) (fields_autoplaced)
    (effects (font (size 1.27 1.27)) (justify right))
    (property "Intersheet References" "${INTERSHEET_REFS}" (id 0) (at 99.5177 127.5556 0)
      (effects (font (size 1.27 1.27)) (justify right) hide)
    )
  )
  (global_label "PCIE1_TX_P" (shape input) (at 115.57 140.335 180) (fields_autoplaced)
    (effects (font (size 1.27 1.27)) (justify right))
    (property "Intersheet References" "${INTERSHEET_REFS}" (id 0) (at 102.3601 140.2556 0)
      (effects (font (size 1.27 1.27)) (justify right) hide)
    )
  )
  (global_label "PCIE1_RST_N" (shape input) (at 115.57 130.175 180) (fields_autoplaced)
    (effects (font (size 1.27 1.27)) (justify right))
    (property "Intersheet References" "${INTERSHEET_REFS}" (id 0) (at 101.0296 130.0956 0)
      (effects (font (size 1.27 1.27)) (justify right) hide)
    )
  )
  (global_label "PCIE1_TX_N" (shape input) (at 115.57 137.795 180) (fields_autoplaced)
    (effects (font (size 1.27 1.27)) (justify right))
    (property "Intersheet References" "${INTERSHEET_REFS}" (id 0) (at 102.2996 137.7156 0)
      (effects (font (size 1.27 1.27)) (justify right) hide)
    )
  )
  (global_label "PAIR36" (shape output) (at 255.27 164.465 180) (fields_autoplaced)
    (effects (font (size 1.27 1.27)) (justify right))
    (property "Intersheet References" "${INTERSHEET_REFS}" (id 0) (at 246.2934 164.3856 0)
      (effects (font (size 1.27 1.27)) (justify right) hide)
    )
  )
  (global_label "PCIE1_RX_P" (shape output) (at 115.57 145.415 180) (fields_autoplaced)
    (effects (font (size 1.27 1.27)) (justify right))
    (property "Intersheet References" "${INTERSHEET_REFS}" (id 0) (at 102.0577 145.3356 0)
      (effects (font (size 1.27 1.27)) (justify right) hide)
    )
  )
  (global_label "PCIE1_REFCLK_N" (shape input) (at 115.57 135.255 180) (fields_autoplaced)
    (effects (font (size 1.27 1.27)) (justify right))
    (property "Intersheet References" "${INTERSHEET_REFS}" (id 0) (at 97.401 135.3344 0)
      (effects (font (size 1.27 1.27)) (justify right) hide)
    )
  )
  (global_label "PCIE1_REFCLK_P" (shape input) (at 115.57 132.715 180) (fields_autoplaced)
    (effects (font (size 1.27 1.27)) (justify right))
    (property "Intersheet References" "${INTERSHEET_REFS}" (id 0) (at 97.4615 132.7944 0)
      (effects (font (size 1.27 1.27)) (justify right) hide)
    )
  )
  (global_label "3V3_SYS" (shape input) (at 92.075 78.74 180) (fields_autoplaced)
    (effects (font (size 1.27 1.27)) (justify right))
    (property "Intersheet References" "${INTERSHEET_REFS}" (id 0) (at 81.7679 78.6606 0)
      (effects (font (size 1.27 1.27)) (justify right) hide)
    )
  )
  (global_label "PAIR78" (shape output) (at 255.27 169.545 180) (fields_autoplaced)
    (effects (font (size 1.27 1.27)) (justify right))
    (property "Intersheet References" "${INTERSHEET_REFS}" (id 0) (at 246.2934 169.4656 0)
      (effects (font (size 1.27 1.27)) (justify right) hide)
    )
  )
  (global_label "PCIE1_CLKREQ_N" (shape output) (at 115.57 125.095 180) (fields_autoplaced)
    (effects (font (size 1.27 1.27)) (justify right))
    (property "Intersheet References" "${INTERSHEET_REFS}" (id 0) (at 97.1591 125.0156 0)
      (effects (font (size 1.27 1.27)) (justify right) hide)
    )
  )
  (global_label "VREG_S4A_1V8" (shape input) (at 123.19 114.935 180) (fields_autoplaced)
    (effects (font (size 1.27 1.27)) (justify right))
    (property "Intersheet References" "${INTERSHEET_REFS}" (id 0) (at 107.1377 114.8556 0)
      (effects (font (size 1.27 1.27)) (justify right) hide)
    )
  )
  (global_label "PAIR12" (shape output) (at 255.27 161.925 180) (fields_autoplaced)
    (effects (font (size 1.27 1.27)) (justify right))
    (property "Intersheet References" "${INTERSHEET_REFS}" (id 0) (at 246.2934 161.8456 0)
      (effects (font (size 1.27 1.27)) (justify right) hide)
    )
  )

  (symbol (lib_id "sa800u-baseboard-hw:C_100n_0402") (at 143.129 145.415 0) (mirror x) (unit 1)
    (in_bom yes) (on_board yes)
    (property "Reference" "C7" (id 0) (at 148.844 144.272 0)
      (effects (font (size 1.524 1.524)))
    )
    (property "Value" "C_100n_0402" (id 1) (at 143.129 141.605 0)
      (effects (font (size 1.524 1.524)) hide)
    )
    (property "Footprint" "sa800u-baseboard-hw-footprints:C_0402_1005Metric" (id 2) (at 148.209 150.495 0)
      (effects (font (size 1.524 1.524)) (justify left) hide)
    )
    (property "Datasheet" "https://search.murata.co.jp/Ceramy/image/img/A01X/G101/ENG/GRM155R61H104KE14-01.pdf" (id 3) (at 143.129 145.415 0)
      (effects (font (size 1.27 1.27)) hide)
    )
    (property "Manufacturer" "Murata" (id 4) (at 148.209 155.575 0)
      (effects (font (size 1.524 1.524)) (justify left) hide)
    )
    (property "MPN" "GRM155R61H104KE14D" (id 5) (at 148.209 153.035 0)
      (effects (font (size 1.524 1.524)) (justify left) hide)
    )
    (property "Val" "100n" (id 6) (at 148.844 146.812 0))
    (property "License" "Apache-2.0" (id 7) (at 163.449 122.555 0)
      (effects (font (size 1.27 1.27) (thickness 0.15)) (justify left bottom) hide)
    )
    (property "Author" "Antmicro" (id 8) (at 163.449 120.015 0)
      (effects (font (size 1.27 1.27) (thickness 0.15)) (justify left bottom) hide)
    )
    (property "Voltage" "50V" (id 9) (at 163.449 117.475 0)
      (effects (font (size 1.27 1.27)) (justify left bottom) hide)
    )
    (property "Dielectric" "X5R" (id 10) (at 163.449 114.935 0)
      (effects (font (size 1.27 1.27)) (justify left bottom) hide)
    )
    (pin "1")
    (pin "2")
  )

  (symbol (lib_id "sa800u-baseboard-hw:C_100n_0402") (at 140.589 142.875 0) (mirror x) (unit 1)
    (in_bom yes) (on_board yes)
    (property "Reference" "C6" (id 0) (at 139.827 141.478 0)
      (effects (font (size 1.524 1.524)))
    )
    (property "Value" "C_100n_0402" (id 1) (at 140.589 139.065 0)
      (effects (font (size 1.524 1.524)) hide)
    )
    (property "Footprint" "sa800u-baseboard-hw-footprints:C_0402_1005Metric" (id 2) (at 145.669 147.955 0)
      (effects (font (size 1.524 1.524)) (justify left) hide)
    )
    (property "Datasheet" "https://search.murata.co.jp/Ceramy/image/img/A01X/G101/ENG/GRM155R61H104KE14-01.pdf" (id 3) (at 140.589 142.875 0)
      (effects (font (size 1.27 1.27)) hide)
    )
    (property "Manufacturer" "Murata" (id 4) (at 145.669 153.035 0)
      (effects (font (size 1.524 1.524)) (justify left) hide)
    )
    (property "MPN" "GRM155R61H104KE14D" (id 5) (at 145.669 150.495 0)
      (effects (font (size 1.524 1.524)) (justify left) hide)
    )
    (property "Val" "100n" (id 6) (at 139.827 144.018 0))
    (property "License" "Apache-2.0" (id 7) (at 160.909 120.015 0)
      (effects (font (size 1.27 1.27) (thickness 0.15)) (justify left bottom) hide)
    )
    (property "Author" "Antmicro" (id 8) (at 160.909 117.475 0)
      (effects (font (size 1.27 1.27) (thickness 0.15)) (justify left bottom) hide)
    )
    (property "Voltage" "50V" (id 9) (at 160.909 114.935 0)
      (effects (font (size 1.27 1.27)) (justify left bottom) hide)
    )
    (property "Dielectric" "X5R" (id 10) (at 160.909 112.395 0)
      (effects (font (size 1.27 1.27)) (justify left bottom) hide)
    )
    (pin "1")
    (pin "2")
  )

  (symbol (lib_id "sa800u-baseboard-hw:R_470R_0402") (at 293.116 161.925 0) (unit 1)
    (in_bom yes) (on_board yes)
    (property "Reference" "R14" (id 0) (at 291.338 160.782 0)
      (effects (font (size 1.524 1.524)))
    )
    (property "Value" "R_470R_0402" (id 1) (at 293.116 165.735 0)
      (effects (font (size 1.524 1.524)) hide)
    )
    (property "Footprint" "sa800u-baseboard-hw-footprints:R_0402_1005Metric" (id 2) (at 298.196 156.845 0)
      (effects (font (size 1.524 1.524)) (justify left) hide)
    )
    (property "Datasheet" "https://www.bourns.com/docs/product-datasheets/cr.pdf" (id 3) (at 293.116 161.925 0)
      (effects (font (size 1.27 1.27)) hide)
    )
    (property "Manufacturer" "Bourns" (id 4) (at 298.196 151.765 0)
      (effects (font (size 1.524 1.524)) (justify left) hide)
    )
    (property "MPN" "CR0402-FX-4700GLF" (id 5) (at 298.196 154.305 0)
      (effects (font (size 1.524 1.524)) (justify left) hide)
    )
    (property "Val" "470R" (id 6) (at 300.101 161.036 0))
    (property "License" "Apache-2.0" (id 7) (at 313.436 187.325 0)
      (effects (font (size 1.27 1.27) (thickness 0.15)) (justify left bottom) hide)
    )
    (property "Author" "Antmicro" (id 8) (at 313.436 189.865 0)
      (effects (font (size 1.27 1.27) (thickness 0.15)) (justify left bottom) hide)
    )
    (property "Tolerance" "1%" (id 9) (at 313.436 172.085 0)
      (effects (font (size 1.27 1.27)) (justify left bottom) hide)
    )
    (pin "1")
    (pin "2")
  )

  (symbol (lib_id "sa800u-baseboard-hw:R_470R_0402") (at 293.116 156.845 0) (mirror x) (unit 1)
    (in_bom yes) (on_board yes)
    (property "Reference" "R13" (id 0) (at 291.338 155.702 0)
      (effects (font (size 1.524 1.524)))
    )
    (property "Value" "R_470R_0402" (id 1) (at 293.116 153.035 0)
      (effects (font (size 1.524 1.524)) hide)
    )
    (property "Footprint" "sa800u-baseboard-hw-footprints:R_0402_1005Metric" (id 2) (at 298.196 161.925 0)
      (effects (font (size 1.524 1.524)) (justify left) hide)
    )
    (property "Datasheet" "https://www.bourns.com/docs/product-datasheets/cr.pdf" (id 3) (at 293.116 156.845 0)
      (effects (font (size 1.27 1.27)) hide)
    )
    (property "Manufacturer" "Bourns" (id 4) (at 298.196 167.005 0)
      (effects (font (size 1.524 1.524)) (justify left) hide)
    )
    (property "MPN" "CR0402-FX-4700GLF" (id 5) (at 298.196 164.465 0)
      (effects (font (size 1.524 1.524)) (justify left) hide)
    )
    (property "Val" "470R" (id 6) (at 300.228 155.829 0))
    (property "License" "Apache-2.0" (id 7) (at 313.436 131.445 0)
      (effects (font (size 1.27 1.27) (thickness 0.15)) (justify left bottom) hide)
    )
    (property "Author" "Antmicro" (id 8) (at 313.436 128.905 0)
      (effects (font (size 1.27 1.27) (thickness 0.15)) (justify left bottom) hide)
    )
    (property "Tolerance" "1%" (id 9) (at 313.436 146.685 0)
      (effects (font (size 1.27 1.27)) (justify left bottom) hide)
    )
    (pin "1")
    (pin "2")
  )

  (symbol (lib_id "sa800u-baseboard-hw:R_1k_0402") (at 134.62 116.078 270) (unit 1)
    (in_bom yes) (on_board yes) (fields_autoplaced)
    (property "Reference" "R7" (id 0) (at 137.16 117.348 90)
      (effects (font (size 1.524 1.524)) (justify left))
    )
    (property "Value" "R_1k_0402" (id 1) (at 130.81 116.078 0)
      (effects (font (size 1.524 1.524)) hide)
    )
    (property "Footprint" "sa800u-baseboard-hw-footprints:R_0402_1005Metric" (id 2) (at 139.7 121.158 0)
      (effects (font (size 1.524 1.524)) (justify left) hide)
    )
    (property "Datasheet" "https://www.bourns.com/docs/product-datasheets/cr.pdf" (id 3) (at 134.62 116.078 0)
      (effects (font (size 1.27 1.27)) hide)
    )
    (property "Manufacturer" "Bourns" (id 4) (at 144.78 121.158 0)
      (effects (font (size 1.524 1.524)) (justify left) hide)
    )
    (property "MPN" "CR0402-FX-1001GLF" (id 5) (at 142.24 121.158 0)
      (effects (font (size 1.524 1.524)) (justify left) hide)
    )
    (property "Val" "1k" (id 6) (at 137.16 120.5229 90)
      (effects (font (size 1.27 1.27)) (justify left))
    )
    (property "License" "Apache-2.0" (id 7) (at 109.22 136.398 0)
      (effects (font (size 1.27 1.27) (thickness 0.15)) (justify left bottom) hide)
    )
    (property "Author" "Antmicro" (id 8) (at 106.68 136.398 0)
      (effects (font (size 1.27 1.27) (thickness 0.15)) (justify left bottom) hide)
    )
    (property "Tolerance" "1%" (id 9) (at 124.46 136.398 0)
      (effects (font (size 1.27 1.27)) (justify left bottom) hide)
    )
    (pin "1")
    (pin "2")
  )

  (symbol (lib_id "sa800u-baseboard-hw:R_1k_0402") (at 152.273 158.115 0) (unit 1)
    (in_bom yes) (on_board yes) (fields_autoplaced)
    (property "Reference" "R9" (id 0) (at 154.813 162.56 0)
      (effects (font (size 1.524 1.524)))
    )
    (property "Value" "R_1k_0402" (id 1) (at 152.273 161.925 0)
      (effects (font (size 1.524 1.524)) hide)
    )
    (property "Footprint" "sa800u-baseboard-hw-footprints:R_0402_1005Metric" (id 2) (at 157.353 153.035 0)
      (effects (font (size 1.524 1.524)) (justify left) hide)
    )
    (property "Datasheet" "https://www.bourns.com/docs/product-datasheets/cr.pdf" (id 3) (at 152.273 158.115 0)
      (effects (font (size 1.27 1.27)) hide)
    )
    (property "Manufacturer" "Bourns" (id 4) (at 157.353 147.955 0)
      (effects (font (size 1.524 1.524)) (justify left) hide)
    )
    (property "MPN" "CR0402-FX-1001GLF" (id 5) (at 157.353 150.495 0)
      (effects (font (size 1.524 1.524)) (justify left) hide)
    )
    (property "Val" "1k" (id 6) (at 154.813 165.1 0))
    (property "License" "Apache-2.0" (id 7) (at 172.593 183.515 0)
      (effects (font (size 1.27 1.27) (thickness 0.15)) (justify left bottom) hide)
    )
    (property "Author" "Antmicro" (id 8) (at 172.593 186.055 0)
      (effects (font (size 1.27 1.27) (thickness 0.15)) (justify left bottom) hide)
    )
    (property "Tolerance" "1%" (id 9) (at 172.593 168.275 0)
      (effects (font (size 1.27 1.27)) (justify left bottom) hide)
    )
    (pin "1")
    (pin "2")
  )

  (symbol (lib_id "sa800u-baseboard-hw:R_10k_0402") (at 126.365 116.078 270) (unit 1)
    (in_bom yes) (on_board yes) (fields_autoplaced)
    (property "Reference" "R6" (id 0) (at 128.27 117.348 90)
      (effects (font (size 1.524 1.524)) (justify left))
    )
    (property "Value" "R_10k_0402" (id 1) (at 122.555 116.078 0)
      (effects (font (size 1.524 1.524)) hide)
    )
    (property "Footprint" "sa800u-baseboard-hw-footprints:R_0402_1005Metric" (id 2) (at 131.445 121.158 0)
      (effects (font (size 1.524 1.524)) (justify left) hide)
    )
    (property "Datasheet" "https://www.bourns.com/docs/product-datasheets/cr.pdf" (id 3) (at 126.365 116.078 0)
      (effects (font (size 1.27 1.27)) hide)
    )
    (property "Manufacturer" "Bourns" (id 4) (at 136.525 121.158 0)
      (effects (font (size 1.524 1.524)) (justify left) hide)
    )
    (property "MPN" "CR0402-FX-1002GLF" (id 5) (at 133.985 121.158 0)
      (effects (font (size 1.524 1.524)) (justify left) hide)
    )
    (property "Val" "10k" (id 6) (at 128.27 120.5229 90)
      (effects (font (size 1.27 1.27)) (justify left))
    )
    (property "License" "Apache-2.0" (id 7) (at 100.965 136.398 0)
      (effects (font (size 1.27 1.27) (thickness 0.15)) (justify left bottom) hide)
    )
    (property "Author" "Antmicro" (id 8) (at 98.425 136.398 0)
      (effects (font (size 1.27 1.27) (thickness 0.15)) (justify left bottom) hide)
    )
    (property "Tolerance" "1%" (id 9) (at 116.205 136.398 0)
      (effects (font (size 1.27 1.27)) (justify left bottom) hide)
    )
    (pin "1")
    (pin "2")
  )

  (symbol (lib_id "sa800u-baseboard-hw:R_10k_0402") (at 142.875 116.078 270) (unit 1)
    (in_bom yes) (on_board yes) (fields_autoplaced)
    (property "Reference" "R8" (id 0) (at 144.78 117.348 90)
      (effects (font (size 1.524 1.524)) (justify left))
    )
    (property "Value" "R_10k_0402" (id 1) (at 139.065 116.078 0)
      (effects (font (size 1.524 1.524)) hide)
    )
    (property "Footprint" "sa800u-baseboard-hw-footprints:R_0402_1005Metric" (id 2) (at 147.955 121.158 0)
      (effects (font (size 1.524 1.524)) (justify left) hide)
    )
    (property "Datasheet" "https://www.bourns.com/docs/product-datasheets/cr.pdf" (id 3) (at 142.875 116.078 0)
      (effects (font (size 1.27 1.27)) hide)
    )
    (property "Manufacturer" "Bourns" (id 4) (at 153.035 121.158 0)
      (effects (font (size 1.524 1.524)) (justify left) hide)
    )
    (property "MPN" "CR0402-FX-1002GLF" (id 5) (at 150.495 121.158 0)
      (effects (font (size 1.524 1.524)) (justify left) hide)
    )
    (property "Val" "10k" (id 6) (at 144.78 120.5229 90)
      (effects (font (size 1.27 1.27)) (justify left))
    )
    (property "License" "Apache-2.0" (id 7) (at 117.475 136.398 0)
      (effects (font (size 1.27 1.27) (thickness 0.15)) (justify left bottom) hide)
    )
    (property "Author" "Antmicro" (id 8) (at 114.935 136.398 0)
      (effects (font (size 1.27 1.27) (thickness 0.15)) (justify left bottom) hide)
    )
    (property "Tolerance" "1%" (id 9) (at 132.715 136.398 0)
      (effects (font (size 1.27 1.27)) (justify left bottom) hide)
    )
    (pin "1")
    (pin "2")
  )

  (symbol (lib_id "sa800u-baseboard-hw:Earth") (at 241.808 178.435 0) (unit 1)
    (in_bom yes) (on_board yes) (fields_autoplaced)
    (property "Reference" "#PWR010" (id 0) (at 241.808 184.785 0)
      (effects (font (size 1.27 1.27)) hide)
    )
    (property "Value" "Earth" (id 1) (at 241.808 182.245 0)
      (effects (font (size 1.27 1.27)) hide)
    )
    (property "Footprint" "" (id 2) (at 241.808 178.435 0)
      (effects (font (size 1.27 1.27)) hide)
    )
    (property "Datasheet" "~" (id 3) (at 241.808 178.435 0)
      (effects (font (size 1.27 1.27)) hide)
    )
    (pin "1")
  )

  (symbol (lib_id "sa800u-baseboard-hw:R_15k_0603") (at 160.655 167.005 270) (unit 1)
    (in_bom yes) (on_board yes) (fields_autoplaced)
    (property "Reference" "R10" (id 0) (at 162.56 168.275 90)
      (effects (font (size 1.524 1.524)) (justify left))
    )
    (property "Value" "R_15k_0603" (id 1) (at 156.845 167.005 0)
      (effects (font (size 1.524 1.524)) hide)
    )
    (property "Footprint" "sa800u-baseboard-hw-footprints:R_0603_1608Metric" (id 2) (at 165.735 172.085 0)
      (effects (font (size 1.524 1.524)) (justify left) hide)
    )
    (property "Datasheet" "https://www.bourns.com/docs/product-datasheets/cr.pdf" (id 3) (at 160.655 167.005 0)
      (effects (font (size 1.27 1.27)) hide)
    )
    (property "Manufacturer" "Bourns" (id 4) (at 170.815 172.085 0)
      (effects (font (size 1.524 1.524)) (justify left) hide)
    )
    (property "MPN" "CR0603-FX-1502ELF" (id 5) (at 168.275 172.085 0)
      (effects (font (size 1.524 1.524)) (justify left) hide)
    )
    (property "Val" "15k" (id 6) (at 162.56 171.4499 90)
      (effects (font (size 1.27 1.27)) (justify left))
    )
    (property "License" "Apache-2.0" (id 7) (at 135.255 187.325 0)
      (effects (font (size 1.27 1.27) (thickness 0.15)) (justify left bottom) hide)
    )
    (property "Author" "Antmicro" (id 8) (at 132.715 187.325 0)
      (effects (font (size 1.27 1.27) (thickness 0.15)) (justify left bottom) hide)
    )
    (property "Tolerance" "1%" (id 9) (at 150.495 187.325 0)
      (effects (font (size 1.27 1.27)) (justify left bottom) hide)
    )
    (pin "1")
    (pin "2")
  )

  (symbol (lib_id "sa800u-baseboard-hw:GND") (at 160.655 172.085 0) (unit 1)
    (in_bom yes) (on_board yes) (fields_autoplaced)
    (property "Reference" "#PWR06" (id 0) (at 160.655 178.435 0)
      (effects (font (size 1.27 1.27)) hide)
    )
    (property "Value" "GND" (id 1) (at 160.655 176.53 0))
    (property "Footprint" "" (id 2) (at 160.655 172.085 0)
      (effects (font (size 1.27 1.27)) hide)
    )
    (property "Datasheet" "" (id 3) (at 160.655 172.085 0)
      (effects (font (size 1.27 1.27)) hide)
    )
    (property "Author" "Antmicro" (id 4) (at 169.545 179.705 0)
      (effects (font (size 1.27 1.27) (thickness 0.15)) (justify left bottom) hide)
    )
    (property "License" "Apache-2.0" (id 5) (at 169.545 182.245 0)
      (effects (font (size 1.27 1.27) (thickness 0.15)) (justify left bottom) hide)
    )
    (pin "1")
  )

  (symbol (lib_id "sa800u-baseboard-hw:RTL8111H") (at 176.53 114.935 0) (unit 1)
    (in_bom yes) (on_board yes) (fields_autoplaced)
    (property "Reference" "U1" (id 0) (at 190.5 106.553 0))
    (property "Value" "RTL8111H" (id 1) (at 190.5 109.093 0))
    (property "Footprint" "sa800u-baseboard-hw-footprints:QFN-32-1EP_4x4mm_P0.4mm" (id 2) (at 176.53 114.935 0)
      (effects (font (size 1.27 1.27)) hide)
    )
    (property "Datasheet" "" (id 3) (at 176.53 114.935 0)
      (effects (font (size 1.27 1.27)) hide)
    )
    (property "MPN" "RTL8111H" (id 4) (at 218.2876 135.128 0)
      (effects (font (size 1.27 1.27)) (justify left) hide)
    )
    (property "Manufacturer" "Realtek" (id 5) (at 218.2876 137.4394 0)
      (effects (font (size 1.27 1.27)) (justify left) hide)
    )
    (property "Author" "Antmicro" (id 6) (at 217.17 132.715 0)
      (effects (font (size 1.27 1.27) (thickness 0.15)) (justify left bottom) hide)
    )
    (property "License" "Apache-2.0" (id 7) (at 217.17 135.255 0)
      (effects (font (size 1.27 1.27) (thickness 0.15)) (justify left bottom) hide)
    )
    (pin "1")
    (pin "10")
    (pin "11")
    (pin "12")
    (pin "13")
    (pin "14")
    (pin "15")
    (pin "16")
    (pin "17")
    (pin "18")
    (pin "19")
    (pin "2")
    (pin "20")
    (pin "21")
    (pin "22")
    (pin "23")
    (pin "24")
    (pin "25")
    (pin "26")
    (pin "27")
    (pin "28")
    (pin "29")
    (pin "3")
    (pin "30")
    (pin "31")
    (pin "32")
    (pin "33")
    (pin "4")
    (pin "5")
    (pin "6")
    (pin "7")
    (pin "8")
    (pin "9")
  )

  (symbol (lib_id "sa800u-baseboard-hw:R_2k49_0402") (at 171.704 164.592 90) (mirror x) (unit 1)
    (in_bom yes) (on_board yes) (fields_autoplaced)
    (property "Reference" "R11" (id 0) (at 174.244 165.862 90)
      (effects (font (size 1.524 1.524)) (justify right))
    )
    (property "Value" "R_2k49_0402" (id 1) (at 184.404 184.912 0)
      (effects (font (size 1.27 1.27) (thickness 0.15)) (justify left bottom) hide)
    )
    (property "Footprint" "sa800u-baseboard-hw-footprints:R_0402_1005Metric" (id 2) (at 186.944 184.912 0)
      (effects (font (size 1.27 1.27) (thickness 0.15)) (justify left bottom) hide)
    )
    (property "Datasheet" "https://www.bourns.com/docs/product-datasheets/cr.pdf" (id 3) (at 189.484 184.912 0)
      (effects (font (size 1.27 1.27) (thickness 0.15)) (justify left bottom) hide)
    )
    (property "Manufacturer" "Bourns" (id 4) (at 194.564 184.912 0)
      (effects (font (size 1.27 1.27) (thickness 0.15)) (justify left bottom) hide)
    )
    (property "MPN" "CR0402-FX-2491GLF" (id 5) (at 192.024 184.912 0)
      (effects (font (size 1.27 1.27) (thickness 0.15)) (justify left bottom) hide)
    )
    (property "Val" "2k49" (id 6) (at 174.244 169.0369 90)
      (effects (font (size 1.27 1.27) (thickness 0.15)) (justify right))
    )
    (property "License" "Apache-2.0" (id 7) (at 197.104 184.912 0)
      (effects (font (size 1.27 1.27) (thickness 0.15)) (justify left bottom) hide)
    )
    (property "Author" "Antmicro" (id 8) (at 199.644 184.912 0)
      (effects (font (size 1.27 1.27) (thickness 0.15)) (justify left bottom) hide)
    )
    (property "Tolerance" "1%" (id 9) (at 181.864 184.912 0)
      (effects (font (size 1.27 1.27)) (justify left bottom) hide)
    )
    (pin "1")
    (pin "2")
  )

  (symbol (lib_id "sa800u-baseboard-hw:C_100n_0402") (at 114.3 81.28 270) (unit 1)
    (in_bom yes) (on_board yes) (fields_autoplaced)
    (property "Reference" "C3" (id 0) (at 116.713 82.5563 90)
      (effects (font (size 1.524 1.524)) (justify left))
    )
    (property "Value" "C_100n_0402" (id 1) (at 110.49 81.28 0)
      (effects (font (size 1.524 1.524)) hide)
    )
    (property "Footprint" "sa800u-baseboard-hw-footprints:C_0402_1005Metric" (id 2) (at 119.38 86.36 0)
      (effects (font (size 1.524 1.524)) (justify left) hide)
    )
    (property "Datasheet" "https://search.murata.co.jp/Ceramy/image/img/A01X/G101/ENG/GRM155R61H104KE14-01.pdf" (id 3) (at 114.3 81.28 0)
      (effects (font (size 1.27 1.27)) hide)
    )
    (property "Manufacturer" "Murata" (id 4) (at 124.46 86.36 0)
      (effects (font (size 1.524 1.524)) (justify left) hide)
    )
    (property "MPN" "GRM155R61H104KE14D" (id 5) (at 121.92 86.36 0)
      (effects (font (size 1.524 1.524)) (justify left) hide)
    )
    (property "Val" "100n" (id 6) (at 116.713 85.7312 90)
      (effects (font (size 1.27 1.27)) (justify left))
    )
    (property "License" "Apache-2.0" (id 7) (at 91.44 101.6 0)
      (effects (font (size 1.27 1.27) (thickness 0.15)) (justify left bottom) hide)
    )
    (property "Author" "Antmicro" (id 8) (at 88.9 101.6 0)
      (effects (font (size 1.27 1.27) (thickness 0.15)) (justify left bottom) hide)
    )
    (property "Voltage" "50V" (id 9) (at 86.36 101.6 0)
      (effects (font (size 1.27 1.27)) (justify left bottom) hide)
    )
    (property "Dielectric" "X5R" (id 10) (at 83.82 101.6 0)
      (effects (font (size 1.27 1.27)) (justify left bottom) hide)
    )
    (pin "1")
    (pin "2")
  )

  (symbol (lib_id "sa800u-baseboard-hw:C_4u7_0402") (at 167.005 81.28 270) (unit 1)
    (in_bom yes) (on_board yes) (fields_autoplaced)
    (property "Reference" "C10" (id 0) (at 170.053 81.2863 90)
      (effects (font (size 1.524 1.524)) (justify left))
    )
    (property "Value" "C_4u7_0402" (id 1) (at 163.195 81.28 0)
      (effects (font (size 1.524 1.524)) hide)
    )
    (property "Footprint" "sa800u-baseboard-hw-footprints:C_0402_1005Metric" (id 2) (at 172.085 86.36 0)
      (effects (font (size 1.524 1.524)) (justify left) hide)
    )
    (property "Datasheet" " " (id 3) (at 167.005 81.28 0)
      (effects (font (size 1.27 1.27)) hide)
    )
    (property "Manufacturer" "Murata" (id 4) (at 177.165 86.36 0)
      (effects (font (size 1.524 1.524)) (justify left) hide)
    )
    (property "MPN" "GRM155R61A475MEAAD" (id 5) (at 174.625 86.36 0)
      (effects (font (size 1.524 1.524)) (justify left) hide)
    )
    (property "Val" "4u7" (id 6) (at 170.053 84.4612 90)
      (effects (font (size 1.27 1.27)) (justify left))
    )
    (property "DNP" "DNP" (id 7) (at 170.053 87.0012 90)
      (effects (font (size 1.27 1.27)) (justify left))
    )
    (property "License" "Apache-2.0" (id 8) (at 144.145 101.6 0)
      (effects (font (size 1.27 1.27) (thickness 0.15)) (justify left bottom) hide)
    )
    (property "Author" "Antmicro" (id 9) (at 141.605 101.6 0)
      (effects (font (size 1.27 1.27) (thickness 0.15)) (justify left bottom) hide)
    )
    (property "Voltage" "" (id 10) (at 139.065 101.6 0)
      (effects (font (size 1.27 1.27)) (justify left bottom) hide)
    )
    (property "Dielectric" "" (id 11) (at 136.525 101.6 0)
      (effects (font (size 1.27 1.27)) (justify left bottom) hide)
    )
    (pin "1")
    (pin "2")
  )

  (symbol (lib_id "sa800u-baseboard-hw:Bus_RJ45_5-2337992-8") (at 266.7 133.985 0) (unit 1)
    (in_bom yes) (on_board yes) (fields_autoplaced)
    (property "Reference" "J1" (id 0) (at 277.495 125.73 0)
      (effects (font (size 1.524 1.524)))
    )
    (property "Value" "Bus_RJ45_5-2337992-8" (id 1) (at 277.495 129.54 0)
      (effects (font (size 1.524 1.524)) hide)
    )
    (property "Footprint" "sa800u-baseboard-hw-footprints:RJ45_5-2337992-8_Horizontal" (id 2) (at 317.5 186.055 0)
      (effects (font (size 1.524 1.524)) hide)
    )
    (property "Datasheet" "https://www.te.com/commerce/DocumentDelivery/DDEController?Action=showdoc&DocId=Customer+Drawing%7F5-2337992-8%7FA%7Fpdf%7FEnglish%7FENG_CD_5-2337992-8_A.pdf%7F5-2337992-8" (id 3) (at 303.53 137.795 0)
      (effects (font (size 1.524 1.524)) hide)
    )
    (property "MPN" "5-2337992-8" (id 4) (at 277.495 128.27 0))
    (property "Manufacturer" "TE Connectivity" (id 5) (at 317.5 130.7846 0)
      (effects (font (size 1.27 1.27)) hide)
    )
    (property "Author" "Antmicro" (id 6) (at 302.26 151.765 0)
      (effects (font (size 1.27 1.27) (thickness 0.15)) (justify left bottom) hide)
    )
    (property "License" "Apache-2.0" (id 7) (at 302.26 154.305 0)
      (effects (font (size 1.27 1.27) (thickness 0.15)) (justify left bottom) hide)
    )
    (pin "1")
    (pin "10")
    (pin "11")
    (pin "12")
    (pin "13")
    (pin "14")
    (pin "15")
    (pin "16")
    (pin "17")
    (pin "18")
    (pin "19")
    (pin "2")
    (pin "20")
    (pin "3")
    (pin "4")
    (pin "5")
    (pin "6")
    (pin "7")
    (pin "8")
    (pin "9")
  )

  (symbol (lib_id "sa800u-baseboard-hw:C_10n_0402") (at 241.808 173.355 270) (unit 1)
    (in_bom yes) (on_board yes) (fields_autoplaced)
    (property "Reference" "C16" (id 0) (at 244.983 174.6313 90)
      (effects (font (size 1.524 1.524)) (justify left))
    )
    (property "Value" "C_10n_0402" (id 1) (at 237.998 173.355 0)
      (effects (font (size 1.524 1.524)) hide)
    )
    (property "Footprint" "sa800u-baseboard-hw-footprints:C_0402_1005Metric" (id 2) (at 246.888 178.435 0)
      (effects (font (size 1.524 1.524)) (justify left) hide)
    )
    (property "Datasheet" "https://search.murata.co.jp/Ceramy/image/img/A01X/G101/ENG/GRM155R71H103KA88-01.pdf" (id 3) (at 241.808 173.355 0)
      (effects (font (size 1.27 1.27)) hide)
    )
    (property "Manufacturer" "Murata" (id 4) (at 251.968 178.435 0)
      (effects (font (size 1.524 1.524)) (justify left) hide)
    )
    (property "MPN" "GRM155R71H103KA88D" (id 5) (at 249.428 178.435 0)
      (effects (font (size 1.524 1.524)) (justify left) hide)
    )
    (property "Val" "10n" (id 6) (at 244.983 177.8062 90)
      (effects (font (size 1.27 1.27)) (justify left))
    )
    (property "License" "Apache-2.0" (id 7) (at 218.948 193.675 0)
      (effects (font (size 1.27 1.27) (thickness 0.15)) (justify left bottom) hide)
    )
    (property "Author" "Antmicro" (id 8) (at 216.408 193.675 0)
      (effects (font (size 1.27 1.27) (thickness 0.15)) (justify left bottom) hide)
    )
    (property "Voltage" "50V" (id 9) (at 213.868 193.675 0)
      (effects (font (size 1.27 1.27)) (justify left bottom) hide)
    )
    (property "Dielectric" "X7R" (id 10) (at 211.328 193.675 0)
      (effects (font (size 1.27 1.27)) (justify left bottom) hide)
    )
    (pin "1")
    (pin "2")
  )

  (symbol (lib_id "sa800u-baseboard-hw:Earth") (at 292.1 172.085 0) (mirror y) (unit 1)
    (in_bom yes) (on_board yes) (fields_autoplaced)
    (property "Reference" "#PWR011" (id 0) (at 292.1 178.435 0)
      (effects (font (size 1.27 1.27)) hide)
    )
    (property "Value" "Earth" (id 1) (at 292.1 175.895 0)
      (effects (font (size 1.27 1.27)) hide)
    )
    (property "Footprint" "" (id 2) (at 292.1 172.085 0)
      (effects (font (size 1.27 1.27)) hide)
    )
    (property "Datasheet" "~" (id 3) (at 292.1 172.085 0)
      (effects (font (size 1.27 1.27)) hide)
    )
    (pin "1")
  )

  (symbol (lib_id "sa800u-baseboard-hw:PWR_FLAG") (at 207.645 114.935 0) (unit 1)
    (in_bom yes) (on_board yes) (fields_autoplaced)
    (property "Reference" "#FLG02" (id 0) (at 207.645 113.03 0)
      (effects (font (size 1.27 1.27)) hide)
    )
    (property "Value" "PWR_FLAG" (id 1) (at 207.645 109.22 0))
    (property "Footprint" "" (id 2) (at 207.645 114.935 0)
      (effects (font (size 1.27 1.27)) hide)
    )
    (property "Datasheet" "~" (id 3) (at 207.645 114.935 0)
      (effects (font (size 1.27 1.27)) hide)
    )
    (pin "1")
  )

  (symbol (lib_id "sa800u-baseboard-hw:PWR_FLAG") (at 258.445 78.105 0) (unit 1)
    (in_bom yes) (on_board yes) (fields_autoplaced)
    (property "Reference" "#FLG03" (id 0) (at 258.445 76.2 0)
      (effects (font (size 1.27 1.27)) hide)
    )
    (property "Value" "PWR_FLAG" (id 1) (at 258.445 72.39 0))
    (property "Footprint" "" (id 2) (at 258.445 78.105 0)
      (effects (font (size 1.27 1.27)) hide)
    )
    (property "Datasheet" "~" (id 3) (at 258.445 78.105 0)
      (effects (font (size 1.27 1.27)) hide)
    )
    (pin "1")
  )

  (symbol (lib_id "sa800u-baseboard-hw:TP_0.75mm_SMD") (at 116.332 77.597 90) (unit 1)
    (in_bom yes) (on_board yes) (fields_autoplaced)
    (property "Reference" "TP1" (id 0) (at 118.11 74.4219 90)
      (effects (font (size 1.27 1.27)) (justify right))
    )
    (property "Value" "TP_0.75mm_SMD" (id 1) (at 118.872 77.597 0)
      (effects (font (size 1.27 1.27)) hide)
    )
    (property "Footprint" "sa800u-baseboard-hw-footprints:TP_SMD_0.75mm" (id 2) (at 111.252 72.517 0)
      (effects (font (size 1.524 1.524)) (justify left) hide)
    )
    (property "Datasheet" "" (id 3) (at 108.712 72.517 0)
      (effects (font (size 1.524 1.524)) (justify left) hide)
    )
    (property "MPN" "" (id 4) (at 131.572 59.817 0)
      (effects (font (size 1.27 1.27) (thickness 0.15)) (justify left bottom) hide)
    )
    (property "Manufacturer" "" (id 5) (at 134.112 59.817 0)
      (effects (font (size 1.27 1.27) (thickness 0.15)) (justify left bottom) hide)
    )
    (property "Author" "Antmicro" (id 6) (at 136.652 59.817 0)
      (effects (font (size 1.27 1.27) (thickness 0.15)) (justify left bottom) hide)
    )
    (property "License" "Apache-2.0" (id 7) (at 139.192 59.817 0)
      (effects (font (size 1.27 1.27) (thickness 0.15)) (justify left bottom) hide)
    )
    (pin "1")
  )

  (symbol (lib_id "sa800u-baseboard-hw:TP_0.75mm_SMD") (at 203.454 76.2 90) (unit 1)
    (in_bom yes) (on_board yes) (fields_autoplaced)
    (property "Reference" "TP7" (id 0) (at 205.232 73.0249 90)
      (effects (font (size 1.27 1.27)) (justify right))
    )
    (property "Value" "TP_0.75mm_SMD" (id 1) (at 205.994 76.2 0)
      (effects (font (size 1.27 1.27)) hide)
    )
    (property "Footprint" "sa800u-baseboard-hw-footprints:TP_SMD_0.75mm" (id 2) (at 198.374 71.12 0)
      (effects (font (size 1.524 1.524)) (justify left) hide)
    )
    (property "Datasheet" "" (id 3) (at 195.834 71.12 0)
      (effects (font (size 1.524 1.524)) (justify left) hide)
    )
    (property "MPN" "" (id 4) (at 218.694 58.42 0)
      (effects (font (size 1.27 1.27) (thickness 0.15)) (justify left bottom) hide)
    )
    (property "Manufacturer" "" (id 5) (at 221.234 58.42 0)
      (effects (font (size 1.27 1.27) (thickness 0.15)) (justify left bottom) hide)
    )
    (property "Author" "Antmicro" (id 6) (at 223.774 58.42 0)
      (effects (font (size 1.27 1.27) (thickness 0.15)) (justify left bottom) hide)
    )
    (property "License" "Apache-2.0" (id 7) (at 226.314 58.42 0)
      (effects (font (size 1.27 1.27) (thickness 0.15)) (justify left bottom) hide)
    )
    (pin "1")
  )

  (symbol (lib_id "sa800u-baseboard-hw:TP_0.75mm_SMD") (at 154.94 123.825 90) (unit 1)
    (in_bom yes) (on_board yes) (fields_autoplaced)
    (property "Reference" "TP2" (id 0) (at 157.353 120.6499 90)
      (effects (font (size 1.27 1.27)) (justify right))
    )
    (property "Value" "TP_0.75mm_SMD" (id 1) (at 157.48 123.825 0)
      (effects (font (size 1.27 1.27)) hide)
    )
    (property "Footprint" "sa800u-baseboard-hw-footprints:TP_SMD_0.75mm" (id 2) (at 149.86 118.745 0)
      (effects (font (size 1.524 1.524)) (justify left) hide)
    )
    (property "Datasheet" "" (id 3) (at 147.32 118.745 0)
      (effects (font (size 1.524 1.524)) (justify left) hide)
    )
    (property "MPN" "" (id 4) (at 170.18 106.045 0)
      (effects (font (size 1.27 1.27) (thickness 0.15)) (justify left bottom) hide)
    )
    (property "Manufacturer" "" (id 5) (at 172.72 106.045 0)
      (effects (font (size 1.27 1.27) (thickness 0.15)) (justify left bottom) hide)
    )
    (property "Author" "Antmicro" (id 6) (at 175.26 106.045 0)
      (effects (font (size 1.27 1.27) (thickness 0.15)) (justify left bottom) hide)
    )
    (property "License" "Apache-2.0" (id 7) (at 177.8 106.045 0)
      (effects (font (size 1.27 1.27) (thickness 0.15)) (justify left bottom) hide)
    )
    (pin "1")
  )

  (symbol (lib_id "sa800u-baseboard-hw:TP_0.75mm_SMD") (at 161.925 123.825 90) (unit 1)
    (in_bom yes) (on_board yes) (fields_autoplaced)
    (property "Reference" "TP4" (id 0) (at 163.322 120.6499 90)
      (effects (font (size 1.27 1.27)) (justify right))
    )
    (property "Value" "TP_0.75mm_SMD" (id 1) (at 164.465 123.825 0)
      (effects (font (size 1.27 1.27)) hide)
    )
    (property "Footprint" "sa800u-baseboard-hw-footprints:TP_SMD_0.75mm" (id 2) (at 156.845 118.745 0)
      (effects (font (size 1.524 1.524)) (justify left) hide)
    )
    (property "Datasheet" "" (id 3) (at 154.305 118.745 0)
      (effects (font (size 1.524 1.524)) (justify left) hide)
    )
    (property "MPN" "" (id 4) (at 177.165 106.045 0)
      (effects (font (size 1.27 1.27) (thickness 0.15)) (justify left bottom) hide)
    )
    (property "Manufacturer" "" (id 5) (at 179.705 106.045 0)
      (effects (font (size 1.27 1.27) (thickness 0.15)) (justify left bottom) hide)
    )
    (property "Author" "Antmicro" (id 6) (at 182.245 106.045 0)
      (effects (font (size 1.27 1.27) (thickness 0.15)) (justify left bottom) hide)
    )
    (property "License" "Apache-2.0" (id 7) (at 184.785 106.045 0)
      (effects (font (size 1.27 1.27) (thickness 0.15)) (justify left bottom) hide)
    )
    (pin "1")
  )

  (symbol (lib_id "sa800u-baseboard-hw:TP_0.75mm_SMD") (at 168.275 123.825 90) (unit 1)
    (in_bom yes) (on_board yes) (fields_autoplaced)
    (property "Reference" "TP5" (id 0) (at 170.307 120.6499 90)
      (effects (font (size 1.27 1.27)) (justify right))
    )
    (property "Value" "TP_0.75mm_SMD" (id 1) (at 170.815 123.825 0)
      (effects (font (size 1.27 1.27)) hide)
    )
    (property "Footprint" "sa800u-baseboard-hw-footprints:TP_SMD_0.75mm" (id 2) (at 163.195 118.745 0)
      (effects (font (size 1.524 1.524)) (justify left) hide)
    )
    (property "Datasheet" "" (id 3) (at 160.655 118.745 0)
      (effects (font (size 1.524 1.524)) (justify left) hide)
    )
    (property "MPN" "" (id 4) (at 183.515 106.045 0)
      (effects (font (size 1.27 1.27) (thickness 0.15)) (justify left bottom) hide)
    )
    (property "Manufacturer" "" (id 5) (at 186.055 106.045 0)
      (effects (font (size 1.27 1.27) (thickness 0.15)) (justify left bottom) hide)
    )
    (property "Author" "Antmicro" (id 6) (at 188.595 106.045 0)
      (effects (font (size 1.27 1.27) (thickness 0.15)) (justify left bottom) hide)
    )
    (property "License" "Apache-2.0" (id 7) (at 191.135 106.045 0)
      (effects (font (size 1.27 1.27) (thickness 0.15)) (justify left bottom) hide)
    )
    (pin "1")
  )

  (symbol (lib_id "sa800u-baseboard-hw:Oscillator_SMD_25MHz_KX-7") (at 104.775 169.545 0) (unit 1)
    (in_bom yes) (on_board yes) (fields_autoplaced)
    (property "Reference" "Y1" (id 0) (at 108.585 162.56 0)
      (effects (font (size 1.524 1.524)))
    )
    (property "Value" "Oscillator_SMD_25MHz_KX-7" (id 1) (at 108.585 163.83 0)
      (effects (font (size 1.27 1.27)) hide)
    )
    (property "Footprint" "sa800u-baseboard-hw-footprints:Oscillator_SMD_Geyer_KX-7-4Pin_3.2x2.5mm" (id 2) (at 158.115 169.545 0)
      (effects (font (size 1.27 1.27)) hide)
    )
    (property "Datasheet" "" (id 3) (at 160.655 167.005 0)
      (effects (font (size 1.27 1.27)) hide)
    )
    (property "MPN" "ABM8G-25.000MHZ-18-D2Y-T" (id 4) (at 108.585 165.1 0)
      (effects (font (size 0.7874 0.7874)))
    )
    (property "Manufacturer" "Abracon" (id 5) (at 109.7026 171.9072 0)
      (effects (font (size 0.7874 0.7874)) (justify left) hide)
    )
    (property "Val" "25MHz" (id 6) (at 127.635 189.865 0)
      (effects (font (size 1.27 1.27) (thickness 0.15)) (justify left bottom) hide)
    )
    (property "Author" "Antmicro" (id 7) (at 127.635 192.405 0)
      (effects (font (size 1.27 1.27) (thickness 0.15)) (justify left bottom) hide)
    )
    (property "License" "Apache-2.0" (id 8) (at 127.635 194.945 0)
      (effects (font (size 1.27 1.27) (thickness 0.15)) (justify left bottom) hide)
    )
    (pin "1")
    (pin "2")
    (pin "3")
    (pin "4")
  )

  (symbol (lib_id "sa800u-baseboard-hw:TP_0.75mm_SMD") (at 160.655 157.48 90) (unit 1)
    (in_bom yes) (on_board yes)
    (property "Reference" "TP3" (id 0) (at 157.607 154.305 90))
    (property "Value" "TP_0.75mm_SMD" (id 1) (at 163.195 157.48 0)
      (effects (font (size 1.27 1.27)) hide)
    )
    (property "Footprint" "sa800u-baseboard-hw-footprints:TP_SMD_0.75mm" (id 2) (at 155.575 152.4 0)
      (effects (font (size 1.524 1.524)) (justify left) hide)
    )
    (property "Datasheet" "" (id 3) (at 153.035 152.4 0)
      (effects (font (size 1.524 1.524)) (justify left) hide)
    )
    (property "MPN" "" (id 4) (at 175.895 139.7 0)
      (effects (font (size 1.27 1.27) (thickness 0.15)) (justify left bottom) hide)
    )
    (property "Manufacturer" "" (id 5) (at 178.435 139.7 0)
      (effects (font (size 1.27 1.27) (thickness 0.15)) (justify left bottom) hide)
    )
    (property "Author" "Antmicro" (id 6) (at 180.975 139.7 0)
      (effects (font (size 1.27 1.27) (thickness 0.15)) (justify left bottom) hide)
    )
    (property "License" "Apache-2.0" (id 7) (at 183.515 139.7 0)
      (effects (font (size 1.27 1.27) (thickness 0.15)) (justify left bottom) hide)
    )
    (pin "1")
  )

  (symbol (lib_id "sa800u-baseboard-hw:C_10p_0402") (at 103.505 170.815 270) (unit 1)
    (in_bom yes) (on_board yes) (fields_autoplaced)
    (property "Reference" "C1" (id 0) (at 100.584 172.0913 90)
      (effects (font (size 1.524 1.524)) (justify right))
    )
    (property "Value" "C_10p_0402" (id 1) (at 99.695 170.815 0)
      (effects (font (size 1.524 1.524)) hide)
    )
    (property "Footprint" "sa800u-baseboard-hw-footprints:C_0402_1005Metric" (id 2) (at 108.585 175.895 0)
      (effects (font (size 1.524 1.524)) (justify left) hide)
    )
    (property "Datasheet" "https://search.murata.co.jp/Ceramy/image/img/A01X/G101/ENG/GCM1555C1H100GA16-01.pdf" (id 3) (at 103.505 170.815 0)
      (effects (font (size 1.27 1.27)) hide)
    )
    (property "Manufacturer" "Murata" (id 4) (at 113.665 175.895 0)
      (effects (font (size 1.524 1.524)) (justify left) hide)
    )
    (property "MPN" "GCM1555C1H100GA16D" (id 5) (at 111.125 175.895 0)
      (effects (font (size 1.524 1.524)) (justify left) hide)
    )
    (property "Val" "10p" (id 6) (at 100.584 175.2662 90)
      (effects (font (size 1.27 1.27)) (justify right))
    )
    (property "License" "Apache-2.0" (id 7) (at 80.645 191.135 0)
      (effects (font (size 1.27 1.27) (thickness 0.15)) (justify left bottom) hide)
    )
    (property "Author" "Antmicro" (id 8) (at 78.105 191.135 0)
      (effects (font (size 1.27 1.27) (thickness 0.15)) (justify left bottom) hide)
    )
    (property "Voltage" "50V" (id 9) (at 75.565 191.135 0)
      (effects (font (size 1.27 1.27)) (justify left bottom) hide)
    )
    (property "Dielectric" "C0G" (id 10) (at 73.025 191.135 0)
      (effects (font (size 1.27 1.27)) (justify left bottom) hide)
    )
    (pin "1")
    (pin "2")
  )

  (symbol (lib_id "sa800u-baseboard-hw:C_10p_0402") (at 113.665 170.815 270) (unit 1)
    (in_bom yes) (on_board yes) (fields_autoplaced)
    (property "Reference" "C2" (id 0) (at 117.221 172.0913 90)
      (effects (font (size 1.524 1.524)) (justify left))
    )
    (property "Value" "C_10p_0402" (id 1) (at 109.855 170.815 0)
      (effects (font (size 1.524 1.524)) hide)
    )
    (property "Footprint" "sa800u-baseboard-hw-footprints:C_0402_1005Metric" (id 2) (at 118.745 175.895 0)
      (effects (font (size 1.524 1.524)) (justify left) hide)
    )
    (property "Datasheet" "https://search.murata.co.jp/Ceramy/image/img/A01X/G101/ENG/GCM1555C1H100GA16-01.pdf" (id 3) (at 113.665 170.815 0)
      (effects (font (size 1.27 1.27)) hide)
    )
    (property "Manufacturer" "Murata" (id 4) (at 123.825 175.895 0)
      (effects (font (size 1.524 1.524)) (justify left) hide)
    )
    (property "MPN" "GCM1555C1H100GA16D" (id 5) (at 121.285 175.895 0)
      (effects (font (size 1.524 1.524)) (justify left) hide)
    )
    (property "Val" "10p" (id 6) (at 117.221 175.2662 90)
      (effects (font (size 1.27 1.27)) (justify left))
    )
    (property "License" "Apache-2.0" (id 7) (at 90.805 191.135 0)
      (effects (font (size 1.27 1.27) (thickness 0.15)) (justify left bottom) hide)
    )
    (property "Author" "Antmicro" (id 8) (at 88.265 191.135 0)
      (effects (font (size 1.27 1.27) (thickness 0.15)) (justify left bottom) hide)
    )
    (property "Voltage" "50V" (id 9) (at 85.725 191.135 0)
      (effects (font (size 1.27 1.27)) (justify left bottom) hide)
    )
    (property "Dielectric" "C0G" (id 10) (at 83.185 191.135 0)
      (effects (font (size 1.27 1.27)) (justify left bottom) hide)
    )
    (pin "1")
    (pin "2")
  )

  (symbol (lib_id "sa800u-baseboard-hw:TP_0.75mm_SMD") (at 170.434 163.195 180) (unit 1)
    (in_bom yes) (on_board yes) (fields_autoplaced)
    (property "Reference" "TP6" (id 0) (at 167.259 159.258 0))
    (property "Value" "TP_0.75mm_SMD" (id 1) (at 170.434 160.655 0)
      (effects (font (size 1.27 1.27)) hide)
    )
    (property "Footprint" "sa800u-baseboard-hw-footprints:TP_SMD_0.75mm" (id 2) (at 165.354 168.275 0)
      (effects (font (size 1.524 1.524)) (justify left) hide)
    )
    (property "Datasheet" "" (id 3) (at 165.354 170.815 0)
      (effects (font (size 1.524 1.524)) (justify left) hide)
    )
    (property "MPN" "" (id 4) (at 152.654 147.955 0)
      (effects (font (size 1.27 1.27) (thickness 0.15)) (justify left bottom) hide)
    )
    (property "Manufacturer" "" (id 5) (at 152.654 145.415 0)
      (effects (font (size 1.27 1.27) (thickness 0.15)) (justify left bottom) hide)
    )
    (property "Author" "Antmicro" (id 6) (at 152.654 142.875 0)
      (effects (font (size 1.27 1.27) (thickness 0.15)) (justify left bottom) hide)
    )
    (property "License" "Apache-2.0" (id 7) (at 152.654 140.335 0)
      (effects (font (size 1.27 1.27) (thickness 0.15)) (justify left bottom) hide)
    )
    (pin "1")
  )

  (symbol (lib_id "sa800u-baseboard-hw:TP_0.75mm_SMD") (at 213.106 76.454 90) (unit 1)
    (in_bom yes) (on_board yes) (fields_autoplaced)
    (property "Reference" "TP8" (id 0) (at 215.392 73.2789 90)
      (effects (font (size 1.27 1.27)) (justify right))
    )
    (property "Value" "TP_0.75mm_SMD" (id 1) (at 215.646 76.454 0)
      (effects (font (size 1.27 1.27)) hide)
    )
    (property "Footprint" "sa800u-baseboard-hw-footprints:TP_SMD_0.75mm" (id 2) (at 208.026 71.374 0)
      (effects (font (size 1.524 1.524)) (justify left) hide)
    )
    (property "Datasheet" "" (id 3) (at 205.486 71.374 0)
      (effects (font (size 1.524 1.524)) (justify left) hide)
    )
    (property "MPN" "" (id 4) (at 228.346 58.674 0)
      (effects (font (size 1.27 1.27) (thickness 0.15)) (justify left bottom) hide)
    )
    (property "Manufacturer" "" (id 5) (at 230.886 58.674 0)
      (effects (font (size 1.27 1.27) (thickness 0.15)) (justify left bottom) hide)
    )
    (property "Author" "Antmicro" (id 6) (at 233.426 58.674 0)
      (effects (font (size 1.27 1.27) (thickness 0.15)) (justify left bottom) hide)
    )
    (property "License" "Apache-2.0" (id 7) (at 235.966 58.674 0)
      (effects (font (size 1.27 1.27) (thickness 0.15)) (justify left bottom) hide)
    )
    (pin "1")
  )

  (symbol (lib_id "sa800u-baseboard-hw:GND") (at 108.585 180.975 0) (unit 1)
    (in_bom yes) (on_board yes) (fields_autoplaced)
    (property "Reference" "#PWR04" (id 0) (at 108.585 187.325 0)
      (effects (font (size 1.27 1.27)) hide)
    )
    (property "Value" "GND" (id 1) (at 108.585 185.42 0))
    (property "Footprint" "" (id 2) (at 108.585 180.975 0)
      (effects (font (size 1.27 1.27)) hide)
    )
    (property "Datasheet" "" (id 3) (at 108.585 180.975 0)
      (effects (font (size 1.27 1.27)) hide)
    )
    (property "Author" "Antmicro" (id 4) (at 117.475 188.595 0)
      (effects (font (size 1.27 1.27) (thickness 0.15)) (justify left bottom) hide)
    )
    (property "License" "Apache-2.0" (id 5) (at 117.475 191.135 0)
      (effects (font (size 1.27 1.27) (thickness 0.15)) (justify left bottom) hide)
    )
    (pin "1")
  )

  (symbol (lib_id "sa800u-baseboard-hw:R_1M_0402") (at 123.19 154.178 90) (unit 1)
    (in_bom yes) (on_board yes) (fields_autoplaced)
    (property "Reference" "R5" (id 0) (at 125.73 149.098 90)
      (effects (font (size 1.524 1.524)) (justify right))
    )
    (property "Value" "R_1M_0402" (id 1) (at 135.89 133.858 0)
      (effects (font (size 1.27 1.27) (thickness 0.15)) (justify left bottom) hide)
    )
    (property "Footprint" "sa800u-baseboard-hw-footprints:R_0402_1005Metric" (id 2) (at 138.43 133.858 0)
      (effects (font (size 1.27 1.27) (thickness 0.15)) (justify left bottom) hide)
    )
    (property "Datasheet" "https://www.bourns.com/docs/product-datasheets/cr.pdf" (id 3) (at 140.97 133.858 0)
      (effects (font (size 1.27 1.27) (thickness 0.15)) (justify left bottom) hide)
    )
    (property "Manufacturer" "Bourns" (id 4) (at 146.05 133.858 0)
      (effects (font (size 1.27 1.27) (thickness 0.15)) (justify left bottom) hide)
    )
    (property "MPN" "CR0402-FX-1004GLF" (id 5) (at 143.51 133.858 0)
      (effects (font (size 1.27 1.27) (thickness 0.15)) (justify left bottom) hide)
    )
    (property "Val" "1M" (id 6) (at 125.73 152.2729 90)
      (effects (font (size 1.27 1.27) (thickness 0.15)) (justify right))
    )
    (property "DNP" "DNP" (id 7) (at 125.73 154.8129 90)
      (effects (font (size 1.27 1.27)) (justify right))
    )
    (property "License" "Apache-2.0" (id 8) (at 148.59 133.858 0)
      (effects (font (size 1.27 1.27) (thickness 0.15)) (justify left bottom) hide)
    )
    (property "Author" "Antmicro" (id 9) (at 151.13 133.858 0)
      (effects (font (size 1.27 1.27) (thickness 0.15)) (justify left bottom) hide)
    )
    (property "Tolerance" "1%" (id 10) (at 133.35 133.858 0)
      (effects (font (size 1.27 1.27)) (justify left bottom) hide)
    )
    (pin "1")
    (pin "2")
  )

  (symbol (lib_id "sa800u-baseboard-hw:C_100n_0402") (at 125.095 81.28 270) (unit 1)
    (in_bom yes) (on_board yes) (fields_autoplaced)
    (property "Reference" "C4" (id 0) (at 128.397 82.5563 90)
      (effects (font (size 1.524 1.524)) (justify left))
    )
    (property "Value" "C_100n_0402" (id 1) (at 121.285 81.28 0)
      (effects (font (size 1.524 1.524)) hide)
    )
    (property "Footprint" "sa800u-baseboard-hw-footprints:C_0402_1005Metric" (id 2) (at 130.175 86.36 0)
      (effects (font (size 1.524 1.524)) (justify left) hide)
    )
    (property "Datasheet" "https://search.murata.co.jp/Ceramy/image/img/A01X/G101/ENG/GRM155R61H104KE14-01.pdf" (id 3) (at 125.095 81.28 0)
      (effects (font (size 1.27 1.27)) hide)
    )
    (property "Manufacturer" "Murata" (id 4) (at 135.255 86.36 0)
      (effects (font (size 1.524 1.524)) (justify left) hide)
    )
    (property "MPN" "GRM155R61H104KE14D" (id 5) (at 132.715 86.36 0)
      (effects (font (size 1.524 1.524)) (justify left) hide)
    )
    (property "Val" "100n" (id 6) (at 128.397 85.7312 90)
      (effects (font (size 1.27 1.27)) (justify left))
    )
    (property "License" "Apache-2.0" (id 7) (at 102.235 101.6 0)
      (effects (font (size 1.27 1.27) (thickness 0.15)) (justify left bottom) hide)
    )
    (property "Author" "Antmicro" (id 8) (at 99.695 101.6 0)
      (effects (font (size 1.27 1.27) (thickness 0.15)) (justify left bottom) hide)
    )
    (property "Voltage" "50V" (id 9) (at 97.155 101.6 0)
      (effects (font (size 1.27 1.27)) (justify left bottom) hide)
    )
    (property "Dielectric" "X5R" (id 10) (at 94.615 101.6 0)
      (effects (font (size 1.27 1.27)) (justify left bottom) hide)
    )
    (pin "1")
    (pin "2")
  )

  (symbol (lib_id "sa800u-baseboard-hw:C_100n_0402") (at 135.89 81.28 270) (unit 1)
    (in_bom yes) (on_board yes) (fields_autoplaced)
    (property "Reference" "C5" (id 0) (at 138.557 82.5563 90)
      (effects (font (size 1.524 1.524)) (justify left))
    )
    (property "Value" "C_100n_0402" (id 1) (at 132.08 81.28 0)
      (effects (font (size 1.524 1.524)) hide)
    )
    (property "Footprint" "sa800u-baseboard-hw-footprints:C_0402_1005Metric" (id 2) (at 140.97 86.36 0)
      (effects (font (size 1.524 1.524)) (justify left) hide)
    )
    (property "Datasheet" "https://search.murata.co.jp/Ceramy/image/img/A01X/G101/ENG/GRM155R61H104KE14-01.pdf" (id 3) (at 135.89 81.28 0)
      (effects (font (size 1.27 1.27)) hide)
    )
    (property "Manufacturer" "Murata" (id 4) (at 146.05 86.36 0)
      (effects (font (size 1.524 1.524)) (justify left) hide)
    )
    (property "MPN" "GRM155R61H104KE14D" (id 5) (at 143.51 86.36 0)
      (effects (font (size 1.524 1.524)) (justify left) hide)
    )
    (property "Val" "100n" (id 6) (at 138.557 85.7312 90)
      (effects (font (size 1.27 1.27)) (justify left))
    )
    (property "License" "Apache-2.0" (id 7) (at 113.03 101.6 0)
      (effects (font (size 1.27 1.27) (thickness 0.15)) (justify left bottom) hide)
    )
    (property "Author" "Antmicro" (id 8) (at 110.49 101.6 0)
      (effects (font (size 1.27 1.27) (thickness 0.15)) (justify left bottom) hide)
    )
    (property "Voltage" "50V" (id 9) (at 107.95 101.6 0)
      (effects (font (size 1.27 1.27)) (justify left bottom) hide)
    )
    (property "Dielectric" "X5R" (id 10) (at 105.41 101.6 0)
      (effects (font (size 1.27 1.27)) (justify left bottom) hide)
    )
    (pin "1")
    (pin "2")
  )

  (symbol (lib_id "sa800u-baseboard-hw:C_4u7_0402") (at 146.685 81.28 270) (unit 1)
    (in_bom yes) (on_board yes) (fields_autoplaced)
    (property "Reference" "C8" (id 0) (at 149.86 81.2863 90)
      (effects (font (size 1.524 1.524)) (justify left))
    )
    (property "Value" "C_4u7_0402" (id 1) (at 142.875 81.28 0)
      (effects (font (size 1.524 1.524)) hide)
    )
    (property "Footprint" "sa800u-baseboard-hw-footprints:C_0402_1005Metric" (id 2) (at 151.765 86.36 0)
      (effects (font (size 1.524 1.524)) (justify left) hide)
    )
    (property "Datasheet" " " (id 3) (at 146.685 81.28 0)
      (effects (font (size 1.27 1.27)) hide)
    )
    (property "Manufacturer" "Murata" (id 4) (at 156.845 86.36 0)
      (effects (font (size 1.524 1.524)) (justify left) hide)
    )
    (property "MPN" "GRM155R61A475MEAAD" (id 5) (at 154.305 86.36 0)
      (effects (font (size 1.524 1.524)) (justify left) hide)
    )
    (property "Val" "4u7" (id 6) (at 149.86 84.4612 90)
      (effects (font (size 1.27 1.27)) (justify left))
    )
    (property "DNP" "DNP" (id 7) (at 149.86 87.0012 90)
      (effects (font (size 1.27 1.27)) (justify left))
    )
    (property "License" "Apache-2.0" (id 8) (at 123.825 101.6 0)
      (effects (font (size 1.27 1.27) (thickness 0.15)) (justify left bottom) hide)
    )
    (property "Author" "Antmicro" (id 9) (at 121.285 101.6 0)
      (effects (font (size 1.27 1.27) (thickness 0.15)) (justify left bottom) hide)
    )
    (property "Voltage" "" (id 10) (at 118.745 101.6 0)
      (effects (font (size 1.27 1.27)) (justify left bottom) hide)
    )
    (property "Dielectric" "" (id 11) (at 116.205 101.6 0)
      (effects (font (size 1.27 1.27)) (justify left bottom) hide)
    )
    (pin "1")
    (pin "2")
  )

  (symbol (lib_id "sa800u-baseboard-hw:C_4u7_0402") (at 156.845 81.28 270) (unit 1)
    (in_bom yes) (on_board yes) (fields_autoplaced)
    (property "Reference" "C9" (id 0) (at 160.147 81.2863 90)
      (effects (font (size 1.524 1.524)) (justify left))
    )
    (property "Value" "C_4u7_0402" (id 1) (at 153.035 81.28 0)
      (effects (font (size 1.524 1.524)) hide)
    )
    (property "Footprint" "sa800u-baseboard-hw-footprints:C_0402_1005Metric" (id 2) (at 161.925 86.36 0)
      (effects (font (size 1.524 1.524)) (justify left) hide)
    )
    (property "Datasheet" " " (id 3) (at 156.845 81.28 0)
      (effects (font (size 1.27 1.27)) hide)
    )
    (property "Manufacturer" "Murata" (id 4) (at 167.005 86.36 0)
      (effects (font (size 1.524 1.524)) (justify left) hide)
    )
    (property "MPN" "GRM155R61A475MEAAD" (id 5) (at 164.465 86.36 0)
      (effects (font (size 1.524 1.524)) (justify left) hide)
    )
    (property "Val" "4u7" (id 6) (at 160.147 84.4612 90)
      (effects (font (size 1.27 1.27)) (justify left))
    )
    (property "DNP" "DNP" (id 7) (at 160.147 87.0012 90)
      (effects (font (size 1.27 1.27)) (justify left))
    )
    (property "License" "Apache-2.0" (id 8) (at 133.985 101.6 0)
      (effects (font (size 1.27 1.27) (thickness 0.15)) (justify left bottom) hide)
    )
    (property "Author" "Antmicro" (id 9) (at 131.445 101.6 0)
      (effects (font (size 1.27 1.27) (thickness 0.15)) (justify left bottom) hide)
    )
    (property "Voltage" "" (id 10) (at 128.905 101.6 0)
      (effects (font (size 1.27 1.27)) (justify left bottom) hide)
    )
    (property "Dielectric" "" (id 11) (at 126.365 101.6 0)
      (effects (font (size 1.27 1.27)) (justify left bottom) hide)
    )
    (pin "1")
    (pin "2")
  )

  (symbol (lib_id "sa800u-baseboard-hw:GND") (at 114.3 91.44 0) (unit 1)
    (in_bom yes) (on_board yes) (fields_autoplaced)
    (property "Reference" "#PWR05" (id 0) (at 114.3 97.79 0)
      (effects (font (size 1.27 1.27)) hide)
    )
    (property "Value" "GND" (id 1) (at 114.3 96.52 0))
    (property "Footprint" "" (id 2) (at 114.3 91.44 0)
      (effects (font (size 1.27 1.27)) hide)
    )
    (property "Datasheet" "" (id 3) (at 114.3 91.44 0)
      (effects (font (size 1.27 1.27)) hide)
    )
    (property "Author" "Antmicro" (id 4) (at 123.19 99.06 0)
      (effects (font (size 1.27 1.27) (thickness 0.15)) (justify left bottom) hide)
    )
    (property "License" "Apache-2.0" (id 5) (at 123.19 101.6 0)
      (effects (font (size 1.27 1.27) (thickness 0.15)) (justify left bottom) hide)
    )
    (pin "1")
  )

  (symbol (lib_id "sa800u-baseboard-hw:C_100n_0402") (at 199.39 80.645 270) (unit 1)
    (in_bom yes) (on_board yes) (fields_autoplaced)
    (property "Reference" "C11" (id 0) (at 196.723 81.9213 90)
      (effects (font (size 1.524 1.524)) (justify right))
    )
    (property "Value" "C_100n_0402" (id 1) (at 195.58 80.645 0)
      (effects (font (size 1.524 1.524)) hide)
    )
    (property "Footprint" "sa800u-baseboard-hw-footprints:C_0402_1005Metric" (id 2) (at 204.47 85.725 0)
      (effects (font (size 1.524 1.524)) (justify left) hide)
    )
    (property "Datasheet" "https://search.murata.co.jp/Ceramy/image/img/A01X/G101/ENG/GRM155R61H104KE14-01.pdf" (id 3) (at 199.39 80.645 0)
      (effects (font (size 1.27 1.27)) hide)
    )
    (property "Manufacturer" "Murata" (id 4) (at 209.55 85.725 0)
      (effects (font (size 1.524 1.524)) (justify left) hide)
    )
    (property "MPN" "GRM155R61H104KE14D" (id 5) (at 207.01 85.725 0)
      (effects (font (size 1.524 1.524)) (justify left) hide)
    )
    (property "Val" "100n" (id 6) (at 196.723 85.0962 90)
      (effects (font (size 1.27 1.27)) (justify right))
    )
    (property "License" "Apache-2.0" (id 7) (at 176.53 100.965 0)
      (effects (font (size 1.27 1.27) (thickness 0.15)) (justify left bottom) hide)
    )
    (property "Author" "Antmicro" (id 8) (at 173.99 100.965 0)
      (effects (font (size 1.27 1.27) (thickness 0.15)) (justify left bottom) hide)
    )
    (property "Voltage" "50V" (id 9) (at 171.45 100.965 0)
      (effects (font (size 1.27 1.27)) (justify left bottom) hide)
    )
    (property "Dielectric" "X5R" (id 10) (at 168.91 100.965 0)
      (effects (font (size 1.27 1.27)) (justify left bottom) hide)
    )
    (pin "1")
    (pin "2")
  )

  (symbol (lib_id "sa800u-baseboard-hw:C_100n_0402") (at 215.9 80.645 270) (unit 1)
    (in_bom yes) (on_board yes) (fields_autoplaced)
    (property "Reference" "C12" (id 0) (at 218.694 81.9213 90)
      (effects (font (size 1.524 1.524)) (justify left))
    )
    (property "Value" "C_100n_0402" (id 1) (at 212.09 80.645 0)
      (effects (font (size 1.524 1.524)) hide)
    )
    (property "Footprint" "sa800u-baseboard-hw-footprints:C_0402_1005Metric" (id 2) (at 220.98 85.725 0)
      (effects (font (size 1.524 1.524)) (justify left) hide)
    )
    (property "Datasheet" "https://search.murata.co.jp/Ceramy/image/img/A01X/G101/ENG/GRM155R61H104KE14-01.pdf" (id 3) (at 215.9 80.645 0)
      (effects (font (size 1.27 1.27)) hide)
    )
    (property "Manufacturer" "Murata" (id 4) (at 226.06 85.725 0)
      (effects (font (size 1.524 1.524)) (justify left) hide)
    )
    (property "MPN" "GRM155R61H104KE14D" (id 5) (at 223.52 85.725 0)
      (effects (font (size 1.524 1.524)) (justify left) hide)
    )
    (property "Val" "100n" (id 6) (at 218.694 85.0962 90)
      (effects (font (size 1.27 1.27)) (justify left))
    )
    (property "License" "Apache-2.0" (id 7) (at 193.04 100.965 0)
      (effects (font (size 1.27 1.27) (thickness 0.15)) (justify left bottom) hide)
    )
    (property "Author" "Antmicro" (id 8) (at 190.5 100.965 0)
      (effects (font (size 1.27 1.27) (thickness 0.15)) (justify left bottom) hide)
    )
    (property "Voltage" "50V" (id 9) (at 187.96 100.965 0)
      (effects (font (size 1.27 1.27)) (justify left bottom) hide)
    )
    (property "Dielectric" "X5R" (id 10) (at 185.42 100.965 0)
      (effects (font (size 1.27 1.27)) (justify left bottom) hide)
    )
    (pin "1")
    (pin "2")
  )

  (symbol (lib_id "sa800u-baseboard-hw:GND") (at 199.39 90.805 0) (unit 1)
    (in_bom yes) (on_board yes) (fields_autoplaced)
    (property "Reference" "#PWR09" (id 0) (at 199.39 97.155 0)
      (effects (font (size 1.27 1.27)) hide)
    )
    (property "Value" "GND" (id 1) (at 199.39 95.25 0))
    (property "Footprint" "" (id 2) (at 199.39 90.805 0)
      (effects (font (size 1.27 1.27)) hide)
    )
    (property "Datasheet" "" (id 3) (at 199.39 90.805 0)
      (effects (font (size 1.27 1.27)) hide)
    )
    (property "Author" "Antmicro" (id 4) (at 208.28 98.425 0)
      (effects (font (size 1.27 1.27) (thickness 0.15)) (justify left bottom) hide)
    )
    (property "License" "Apache-2.0" (id 5) (at 208.28 100.965 0)
      (effects (font (size 1.27 1.27) (thickness 0.15)) (justify left bottom) hide)
    )
    (pin "1")
  )

  (symbol (lib_id "sa800u-baseboard-hw:R_0R_0402") (at 206.375 78.105 0) (unit 1)
    (in_bom yes) (on_board yes) (fields_autoplaced)
    (property "Reference" "R12" (id 0) (at 208.915 82.55 0)
      (effects (font (size 1.524 1.524)))
    )
    (property "Value" "R_0R_0402" (id 1) (at 206.375 81.915 0)
      (effects (font (size 1.524 1.524)) hide)
    )
    (property "Footprint" "sa800u-baseboard-hw-footprints:R_0402_1005Metric" (id 2) (at 211.455 73.025 0)
      (effects (font (size 1.524 1.524)) (justify left) hide)
    )
    (property "Datasheet" "https://industrial.panasonic.com/cdbs/www-data/pdf/RDA0000/AOA0000C301.pdf" (id 3) (at 206.375 78.105 0)
      (effects (font (size 1.27 1.27)) hide)
    )
    (property "Manufacturer" "Panasonic" (id 4) (at 211.455 67.945 0)
      (effects (font (size 1.524 1.524)) (justify left) hide)
    )
    (property "MPN" "ERJ2GE0R00X" (id 5) (at 211.455 70.485 0)
      (effects (font (size 1.524 1.524)) (justify left) hide)
    )
    (property "Val" "0R" (id 6) (at 208.915 85.09 0))
    (property "License" "Apache-2.0" (id 7) (at 226.695 103.505 0)
      (effects (font (size 1.27 1.27) (thickness 0.15)) (justify left bottom) hide)
    )
    (property "Author" "Antmicro" (id 8) (at 226.695 106.045 0)
      (effects (font (size 1.27 1.27) (thickness 0.15)) (justify left bottom) hide)
    )
    (property "Tolerance" "~" (id 9) (at 226.695 88.265 0)
      (effects (font (size 1.27 1.27)) (justify left bottom) hide)
    )
    (property "Current" "1A" (id 10) (at 226.695 108.585 0)
      (effects (font (size 1.27 1.27) (thickness 0.15)) (justify left bottom) hide)
    )
    (pin "1")
    (pin "2")
  )

  (symbol (lib_id "sa800u-baseboard-hw:C_100n_0402") (at 226.695 80.645 270) (unit 1)
    (in_bom yes) (on_board yes) (fields_autoplaced)
    (property "Reference" "C13" (id 0) (at 229.743 81.9213 90)
      (effects (font (size 1.524 1.524)) (justify left))
    )
    (property "Value" "C_100n_0402" (id 1) (at 222.885 80.645 0)
      (effects (font (size 1.524 1.524)) hide)
    )
    (property "Footprint" "sa800u-baseboard-hw-footprints:C_0402_1005Metric" (id 2) (at 231.775 85.725 0)
      (effects (font (size 1.524 1.524)) (justify left) hide)
    )
    (property "Datasheet" "https://search.murata.co.jp/Ceramy/image/img/A01X/G101/ENG/GRM155R61H104KE14-01.pdf" (id 3) (at 226.695 80.645 0)
      (effects (font (size 1.27 1.27)) hide)
    )
    (property "Manufacturer" "Murata" (id 4) (at 236.855 85.725 0)
      (effects (font (size 1.524 1.524)) (justify left) hide)
    )
    (property "MPN" "GRM155R61H104KE14D" (id 5) (at 234.315 85.725 0)
      (effects (font (size 1.524 1.524)) (justify left) hide)
    )
    (property "Val" "100n" (id 6) (at 229.743 85.0962 90)
      (effects (font (size 1.27 1.27)) (justify left))
    )
    (property "License" "Apache-2.0" (id 7) (at 203.835 100.965 0)
      (effects (font (size 1.27 1.27) (thickness 0.15)) (justify left bottom) hide)
    )
    (property "Author" "Antmicro" (id 8) (at 201.295 100.965 0)
      (effects (font (size 1.27 1.27) (thickness 0.15)) (justify left bottom) hide)
    )
    (property "Voltage" "50V" (id 9) (at 198.755 100.965 0)
      (effects (font (size 1.27 1.27)) (justify left bottom) hide)
    )
    (property "Dielectric" "X5R" (id 10) (at 196.215 100.965 0)
      (effects (font (size 1.27 1.27)) (justify left bottom) hide)
    )
    (pin "1")
    (pin "2")
  )

  (symbol (lib_id "sa800u-baseboard-hw:C_100n_0402") (at 237.49 80.645 270) (unit 1)
    (in_bom yes) (on_board yes) (fields_autoplaced)
    (property "Reference" "C14" (id 0) (at 239.903 81.9213 90)
      (effects (font (size 1.524 1.524)) (justify left))
    )
    (property "Value" "C_100n_0402" (id 1) (at 233.68 80.645 0)
      (effects (font (size 1.524 1.524)) hide)
    )
    (property "Footprint" "sa800u-baseboard-hw-footprints:C_0402_1005Metric" (id 2) (at 242.57 85.725 0)
      (effects (font (size 1.524 1.524)) (justify left) hide)
    )
    (property "Datasheet" "https://search.murata.co.jp/Ceramy/image/img/A01X/G101/ENG/GRM155R61H104KE14-01.pdf" (id 3) (at 237.49 80.645 0)
      (effects (font (size 1.27 1.27)) hide)
    )
    (property "Manufacturer" "Murata" (id 4) (at 247.65 85.725 0)
      (effects (font (size 1.524 1.524)) (justify left) hide)
    )
    (property "MPN" "GRM155R61H104KE14D" (id 5) (at 245.11 85.725 0)
      (effects (font (size 1.524 1.524)) (justify left) hide)
    )
    (property "Val" "100n" (id 6) (at 239.903 85.0962 90)
      (effects (font (size 1.27 1.27)) (justify left))
    )
    (property "License" "Apache-2.0" (id 7) (at 214.63 100.965 0)
      (effects (font (size 1.27 1.27) (thickness 0.15)) (justify left bottom) hide)
    )
    (property "Author" "Antmicro" (id 8) (at 212.09 100.965 0)
      (effects (font (size 1.27 1.27) (thickness 0.15)) (justify left bottom) hide)
    )
    (property "Voltage" "50V" (id 9) (at 209.55 100.965 0)
      (effects (font (size 1.27 1.27)) (justify left bottom) hide)
    )
    (property "Dielectric" "X5R" (id 10) (at 207.01 100.965 0)
      (effects (font (size 1.27 1.27)) (justify left bottom) hide)
    )
    (pin "1")
    (pin "2")
  )

  (symbol (lib_id "sa800u-baseboard-hw:C_100n_0402") (at 248.285 80.645 270) (unit 1)
    (in_bom yes) (on_board yes) (fields_autoplaced)
    (property "Reference" "C15" (id 0) (at 251.587 81.9213 90)
      (effects (font (size 1.524 1.524)) (justify left))
    )
    (property "Value" "C_100n_0402" (id 1) (at 244.475 80.645 0)
      (effects (font (size 1.524 1.524)) hide)
    )
    (property "Footprint" "sa800u-baseboard-hw-footprints:C_0402_1005Metric" (id 2) (at 253.365 85.725 0)
      (effects (font (size 1.524 1.524)) (justify left) hide)
    )
    (property "Datasheet" "https://search.murata.co.jp/Ceramy/image/img/A01X/G101/ENG/GRM155R61H104KE14-01.pdf" (id 3) (at 248.285 80.645 0)
      (effects (font (size 1.27 1.27)) hide)
    )
    (property "Manufacturer" "Murata" (id 4) (at 258.445 85.725 0)
      (effects (font (size 1.524 1.524)) (justify left) hide)
    )
    (property "MPN" "GRM155R61H104KE14D" (id 5) (at 255.905 85.725 0)
      (effects (font (size 1.524 1.524)) (justify left) hide)
    )
    (property "Val" "100n" (id 6) (at 251.587 85.0962 90)
      (effects (font (size 1.27 1.27)) (justify left))
    )
    (property "License" "Apache-2.0" (id 7) (at 225.425 100.965 0)
      (effects (font (size 1.27 1.27) (thickness 0.15)) (justify left bottom) hide)
    )
    (property "Author" "Antmicro" (id 8) (at 222.885 100.965 0)
      (effects (font (size 1.27 1.27) (thickness 0.15)) (justify left bottom) hide)
    )
    (property "Voltage" "50V" (id 9) (at 220.345 100.965 0)
      (effects (font (size 1.27 1.27)) (justify left bottom) hide)
    )
    (property "Dielectric" "X5R" (id 10) (at 217.805 100.965 0)
      (effects (font (size 1.27 1.27)) (justify left bottom) hide)
    )
    (pin "1")
    (pin "2")
  )

  (symbol (lib_id "sa800u-baseboard-hw:C_1u_0402") (at 258.445 80.645 270) (unit 1)
    (in_bom yes) (on_board yes) (fields_autoplaced)
    (property "Reference" "C17" (id 0) (at 261.62 80.6513 90)
      (effects (font (size 1.524 1.524)) (justify left))
    )
    (property "Value" "C_1u_0402" (id 1) (at 254.635 80.645 0)
      (effects (font (size 1.524 1.524)) hide)
    )
    (property "Footprint" "sa800u-baseboard-hw-footprints:C_0402_1005Metric" (id 2) (at 263.525 85.725 0)
      (effects (font (size 1.524 1.524)) (justify left) hide)
    )
    (property "Datasheet" " " (id 3) (at 258.445 80.645 0)
      (effects (font (size 1.27 1.27)) hide)
    )
    (property "Manufacturer" "TDK" (id 4) (at 268.605 85.725 0)
      (effects (font (size 1.524 1.524)) (justify left) hide)
    )
    (property "MPN" "C1005X6S1A105K050BC" (id 5) (at 266.065 85.725 0)
      (effects (font (size 1.524 1.524)) (justify left) hide)
    )
    (property "Val" "1u" (id 6) (at 261.62 83.8262 90)
      (effects (font (size 1.27 1.27)) (justify left))
    )
    (property "DNP" "DNP" (id 7) (at 261.62 86.3662 90)
      (effects (font (size 1.27 1.27)) (justify left))
    )
    (property "License" "Apache-2.0" (id 8) (at 235.585 100.965 0)
      (effects (font (size 1.27 1.27) (thickness 0.15)) (justify left bottom) hide)
    )
    (property "Author" "Antmicro" (id 9) (at 233.045 100.965 0)
      (effects (font (size 1.27 1.27) (thickness 0.15)) (justify left bottom) hide)
    )
    (property "Voltage" "" (id 10) (at 230.505 100.965 0)
      (effects (font (size 1.27 1.27)) (justify left bottom) hide)
    )
    (property "Dielectric" "" (id 11) (at 227.965 100.965 0)
      (effects (font (size 1.27 1.27)) (justify left bottom) hide)
    )
    (pin "1")
    (pin "2")
  )

  (symbol (lib_id "sa800u-baseboard-hw:FB_120Z_3A_0603") (at 95.377 78.74 0) (unit 1)
    (in_bom yes) (on_board yes) (fields_autoplaced)
    (property "Reference" "FB1" (id 0) (at 97.8789 71.12 0)
      (effects (font (size 1.524 1.524)))
    )
    (property "Value" "FB_120Z_3A_0603" (id 1) (at 97.8789 74.93 0)
      (effects (font (size 1.524 1.524)))
    )
    (property "Footprint" "sa800u-baseboard-hw-footprints:FB_0603_1608Metric" (id 2) (at 100.457 73.66 0)
      (effects (font (size 1.524 1.524)) (justify left) hide)
    )
    (property "Datasheet" "https://www.murata.com/en-global/api/pdfdownloadapi?cate=luNoiseSupprFilteChipFerriBead&partno=BLM18SG121TN1%23" (id 3) (at 100.457 71.12 0)
      (effects (font (size 1.524 1.524)) (justify left) hide)
    )
    (property "MPN" "BLM18SG121TN1D" (id 4) (at 100.457 66.04 0)
      (effects (font (size 1.524 1.524)) (justify left) hide)
    )
    (property "Manufacturer" "Murata" (id 5) (at 100.457 50.8 0)
      (effects (font (size 1.524 1.524)) (justify left) hide)
    )
    (property "Author" "Antmicro" (id 6) (at 109.347 93.98 0)
      (effects (font (size 1.27 1.27) (thickness 0.15)) (justify left bottom) hide)
    )
    (property "License" "Apache-2.0" (id 7) (at 109.347 96.52 0)
      (effects (font (size 1.27 1.27) (thickness 0.15)) (justify left bottom) hide)
    )
    (pin "1")
    (pin "2")
  )

  (symbol (lib_id "sa800u-baseboard-hw:GND") (at 171.704 172.085 0) (mirror y) (unit 1)
    (in_bom yes) (on_board yes) (fields_autoplaced)
    (property "Reference" "#PWR07" (id 0) (at 171.704 178.435 0)
      (effects (font (size 1.27 1.27)) hide)
    )
    (property "Value" "GND" (id 1) (at 171.704 176.53 0))
    (property "Footprint" "" (id 2) (at 171.704 172.085 0)
      (effects (font (size 1.27 1.27)) hide)
    )
    (property "Datasheet" "" (id 3) (at 171.704 172.085 0)
      (effects (font (size 1.27 1.27)) hide)
    )
    (property "Author" "Antmicro" (id 4) (at 162.814 179.705 0)
      (effects (font (size 1.27 1.27) (thickness 0.15)) (justify left bottom) hide)
    )
    (property "License" "Apache-2.0" (id 5) (at 162.814 182.245 0)
      (effects (font (size 1.27 1.27) (thickness 0.15)) (justify left bottom) hide)
    )
    (pin "1")
  )

  (symbol (lib_id "sa800u-baseboard-hw:PWR_FLAG") (at 156.845 78.74 0) (unit 1)
    (in_bom yes) (on_board yes) (fields_autoplaced)
    (property "Reference" "#FLG01" (id 0) (at 156.845 76.835 0)
      (effects (font (size 1.27 1.27)) hide)
    )
    (property "Value" "PWR_FLAG" (id 1) (at 156.845 73.66 0))
    (property "Footprint" "" (id 2) (at 156.845 78.74 0)
      (effects (font (size 1.27 1.27)) hide)
    )
    (property "Datasheet" "~" (id 3) (at 156.845 78.74 0)
      (effects (font (size 1.27 1.27)) hide)
    )
    (pin "1")
  )

  (symbol (lib_id "sa800u-baseboard-hw:PWR_FLAG") (at 292.1 169.291 0) (unit 1)
    (in_bom yes) (on_board yes)
    (property "Reference" "#FLG028" (id 0) (at 292.1 167.386 0)
      (effects (font (size 1.27 1.27)) hide)
    )
    (property "Value" "PWR_FLAG" (id 1) (at 292.1 165.608 0))
    (property "Footprint" "" (id 2) (at 292.1 169.291 0)
      (effects (font (size 1.27 1.27)) hide)
    )
    (property "Datasheet" "~" (id 3) (at 292.1 169.291 0)
      (effects (font (size 1.27 1.27)) hide)
    )
    (pin "1")
  )
)
